(kicad_sch
	(version 20250114)
	(generator "eeschema")
	(generator_version "9.0")
	(paper "A3")
	(title_block
		(title "COM Express 7 Baseboard")
		(date "2025-02-04")
		(rev "1.1.2")
		(company "Antmicro Ltd")
		(comment 1 "www.antmicro.com")
	)
	(bus_alias "SFI"
		(members "RX+" "RX-" "TX+" "TX-")
	)
	(text "CH A internally rerouted to CH B\nLink training disabled for CH B\nSee: https://e2e.ti.com/support/interface-group/interface/f/interface-forum/703878/tlk10034-10gbase-kr-to-sfi-sfp"
		(exclude_from_sim no)
		(at 264.16 123.19 0)
		(effects
			(font
				(size 1.27 1.27)
			)
			(justify left bottom)
		)
	)
	(text "10GKR to SFI"
		(exclude_from_sim no)
		(at 195.58 33.782 0)
		(effects
			(font
				(size 2 2)
				(thickness 0.4)
				(bold yes)
			)
			(justify left bottom)
		)
	)
	(junction
		(at 107.95 76.2)
		(diameter 0)
		(color 0 0 0 0)
	)
	(junction
		(at 304.8 86.36)
		(diameter 0)
		(color 0 0 0 0)
	)
	(junction
		(at 276.86 231.14)
		(diameter 0)
		(color 0 0 0 0)
	)
	(junction
		(at 307.34 83.82)
		(diameter 0)
		(color 0 0 0 0)
	)
	(junction
		(at 110.49 78.74)
		(diameter 0)
		(color 0 0 0 0)
	)
	(junction
		(at 287.02 162.56)
		(diameter 0)
		(color 0 0 0 0)
	)
	(junction
		(at 287.02 185.42)
		(diameter 0)
		(color 0 0 0 0)
	)
	(junction
		(at 118.11 86.36)
		(diameter 0)
		(color 0 0 0 0)
	)
	(junction
		(at 245.11 226.06)
		(diameter 0)
		(color 0 0 0 0)
	)
	(junction
		(at 193.04 243.84)
		(diameter 0)
		(color 0 0 0 0)
	)
	(junction
		(at 200.66 241.3)
		(diameter 0)
		(color 0 0 0 0)
	)
	(junction
		(at 342.9 193.04)
		(diameter 0)
		(color 0 0 0 0)
	)
	(junction
		(at 144.78 185.42)
		(diameter 0)
		(color 0 0 0 0)
	)
	(junction
		(at 342.9 213.36)
		(diameter 0)
		(color 0 0 0 0)
	)
	(junction
		(at 62.23 190.5)
		(diameter 0)
		(color 0 0 0 0)
	)
	(junction
		(at 317.5 162.56)
		(diameter 0)
		(color 0 0 0 0)
	)
	(junction
		(at 327.66 208.28)
		(diameter 0)
		(color 0 0 0 0)
	)
	(junction
		(at 139.7 185.42)
		(diameter 0)
		(color 0 0 0 0)
	)
	(junction
		(at 276.86 208.28)
		(diameter 0)
		(color 0 0 0 0)
	)
	(junction
		(at 125.73 214.63)
		(diameter 0)
		(color 0 0 0 0)
	)
	(junction
		(at 312.42 78.74)
		(diameter 0)
		(color 0 0 0 0)
	)
	(junction
		(at 287.02 231.14)
		(diameter 0)
		(color 0 0 0 0)
	)
	(junction
		(at 317.5 208.28)
		(diameter 0)
		(color 0 0 0 0)
	)
	(junction
		(at 307.34 162.56)
		(diameter 0)
		(color 0 0 0 0)
	)
	(junction
		(at 66.04 190.5)
		(diameter 0)
		(color 0 0 0 0)
	)
	(junction
		(at 327.66 162.56)
		(diameter 0)
		(color 0 0 0 0)
	)
	(junction
		(at 307.34 185.42)
		(diameter 0)
		(color 0 0 0 0)
	)
	(junction
		(at 199.39 115.57)
		(diameter 0)
		(color 0 0 0 0)
	)
	(junction
		(at 297.18 185.42)
		(diameter 0)
		(color 0 0 0 0)
	)
	(junction
		(at 115.57 83.82)
		(diameter 0)
		(color 0 0 0 0)
	)
	(junction
		(at 314.96 76.2)
		(diameter 0)
		(color 0 0 0 0)
	)
	(junction
		(at 276.86 185.42)
		(diameter 0)
		(color 0 0 0 0)
	)
	(junction
		(at 74.93 212.09)
		(diameter 0)
		(color 0 0 0 0)
	)
	(junction
		(at 342.9 185.42)
		(diameter 0)
		(color 0 0 0 0)
	)
	(junction
		(at 287.02 208.28)
		(diameter 0)
		(color 0 0 0 0)
	)
	(junction
		(at 342.9 203.2)
		(diameter 0)
		(color 0 0 0 0)
	)
	(junction
		(at 276.86 162.56)
		(diameter 0)
		(color 0 0 0 0)
	)
	(junction
		(at 307.34 208.28)
		(diameter 0)
		(color 0 0 0 0)
	)
	(junction
		(at 101.6 226.06)
		(diameter 0)
		(color 0 0 0 0)
	)
	(junction
		(at 297.18 208.28)
		(diameter 0)
		(color 0 0 0 0)
	)
	(junction
		(at 105.41 212.09)
		(diameter 0)
		(color 0 0 0 0)
	)
	(junction
		(at 297.18 162.56)
		(diameter 0)
		(color 0 0 0 0)
	)
	(no_connect
		(at 232.41 96.52)
	)
	(no_connect
		(at 232.41 78.74)
	)
	(no_connect
		(at 181.61 86.36)
	)
	(no_connect
		(at 232.41 88.9)
	)
	(no_connect
		(at 232.41 81.28)
	)
	(no_connect
		(at 181.61 88.9)
	)
	(no_connect
		(at 181.61 99.06)
	)
	(no_connect
		(at 181.61 81.28)
	)
	(no_connect
		(at 232.41 111.76)
	)
	(no_connect
		(at 181.61 73.66)
	)
	(no_connect
		(at 181.61 76.2)
	)
	(no_connect
		(at 181.61 71.12)
	)
	(no_connect
		(at 181.61 78.74)
	)
	(no_connect
		(at 181.61 93.98)
	)
	(no_connect
		(at 181.61 101.6)
	)
	(no_connect
		(at 232.41 76.2)
	)
	(no_connect
		(at 181.61 111.76)
	)
	(no_connect
		(at 181.61 96.52)
	)
	(no_connect
		(at 181.61 109.22)
	)
	(no_connect
		(at 232.41 93.98)
	)
	(no_connect
		(at 232.41 73.66)
	)
	(no_connect
		(at 232.41 109.22)
	)
	(no_connect
		(at 232.41 86.36)
	)
	(no_connect
		(at 232.41 83.82)
	)
	(no_connect
		(at 181.61 106.68)
	)
	(no_connect
		(at 181.61 104.14)
	)
	(no_connect
		(at 232.41 71.12)
	)
	(no_connect
		(at 181.61 83.82)
	)
	(no_connect
		(at 232.41 99.06)
	)
	(no_connect
		(at 232.41 104.14)
	)
	(no_connect
		(at 232.41 101.6)
	)
	(no_connect
		(at 232.41 106.68)
	)
	(bus_entry
		(at 93.98 74.93)
		(size 1.27 1.27)
		(stroke
			(width 0)
			(type default)
		)
	)
	(bus_entry
		(at 60.96 229.87)
		(size 1.27 1.27)
		(stroke
			(width 0)
			(type default)
		)
	)
	(bus_entry
		(at 93.98 77.47)
		(size 1.27 1.27)
		(stroke
			(width 0)
			(type default)
		)
	)
	(bus_entry
		(at 325.12 74.93)
		(size -1.27 1.27)
		(stroke
			(width 0)
			(type default)
		)
	)
	(bus_entry
		(at 93.98 82.55)
		(size 1.27 1.27)
		(stroke
			(width 0)
			(type default)
		)
	)
	(bus_entry
		(at 325.12 85.09)
		(size -1.27 1.27)
		(stroke
			(width 0)
			(type default)
		)
	)
	(bus_entry
		(at 93.98 85.09)
		(size 1.27 1.27)
		(stroke
			(width 0)
			(type default)
		)
	)
	(bus_entry
		(at 325.12 82.55)
		(size -1.27 1.27)
		(stroke
			(width 0)
			(type default)
		)
	)
	(bus_entry
		(at 60.96 227.33)
		(size 1.27 1.27)
		(stroke
			(width 0)
			(type default)
		)
	)
	(bus_entry
		(at 325.12 77.47)
		(size -1.27 1.27)
		(stroke
			(width 0)
			(type default)
		)
	)
	(wire
		(pts
			(xy 337.82 213.36) (xy 342.9 213.36)
		)
		(stroke
			(width 0)
			(type default)
		)
	)
	(wire
		(pts
			(xy 123.19 182.88) (xy 124.46 182.88)
		)
		(stroke
			(width 0)
			(type default)
		)
	)
	(wire
		(pts
			(xy 245.11 226.06) (xy 245.11 245.11)
		)
		(stroke
			(width 0)
			(type default)
		)
	)
	(wire
		(pts
			(xy 78.74 233.68) (xy 78.74 234.95)
		)
		(stroke
			(width 0)
			(type default)
		)
	)
	(wire
		(pts
			(xy 342.9 185.42) (xy 342.9 162.56)
		)
		(stroke
			(width 0)
			(type default)
		)
	)
	(wire
		(pts
			(xy 342.9 200.66) (xy 342.9 203.2)
		)
		(stroke
			(width 0)
			(type default)
		)
	)
	(wire
		(pts
			(xy 223.52 233.68) (xy 223.52 245.11)
		)
		(stroke
			(width 0)
			(type default)
		)
	)
	(wire
		(pts
			(xy 276.86 207.01) (xy 276.86 208.28)
		)
		(stroke
			(width 0)
			(type default)
		)
	)
	(wire
		(pts
			(xy 190.5 236.22) (xy 215.9 236.22)
		)
		(stroke
			(width 0)
			(type default)
		)
	)
	(wire
		(pts
			(xy 74.93 210.82) (xy 74.93 212.09)
		)
		(stroke
			(width 0)
			(type default)
		)
	)
	(wire
		(pts
			(xy 74.93 218.44) (xy 74.93 219.71)
		)
		(stroke
			(width 0)
			(type default)
		)
	)
	(wire
		(pts
			(xy 312.42 71.12) (xy 312.42 78.74)
		)
		(stroke
			(width 0)
			(type default)
		)
	)
	(wire
		(pts
			(xy 66.04 190.5) (xy 80.01 190.5)
		)
		(stroke
			(width 0)
			(type default)
		)
	)
	(wire
		(pts
			(xy 149.86 205.74) (xy 160.02 205.74)
		)
		(stroke
			(width 0)
			(type default)
		)
	)
	(wire
		(pts
			(xy 208.28 238.76) (xy 208.28 245.11)
		)
		(stroke
			(width 0)
			(type default)
		)
	)
	(wire
		(pts
			(xy 215.9 236.22) (xy 215.9 245.11)
		)
		(stroke
			(width 0)
			(type default)
		)
	)
	(wire
		(pts
			(xy 160.02 220.98) (xy 134.62 220.98)
		)
		(stroke
			(width 0)
			(type default)
		)
	)
	(bus
		(pts
			(xy 48.26 69.85) (xy 91.44 69.85)
		)
		(stroke
			(width 0)
			(type default)
		)
	)
	(wire
		(pts
			(xy 140.97 238.76) (xy 160.02 238.76)
		)
		(stroke
			(width 0)
			(type default)
		)
	)
	(wire
		(pts
			(xy 378.46 215.9) (xy 378.46 218.44)
		)
		(stroke
			(width 0)
			(type default)
		)
	)
	(wire
		(pts
			(xy 118.11 190.5) (xy 120.65 193.04)
		)
		(stroke
			(width 0)
			(type default)
		)
	)
	(wire
		(pts
			(xy 307.34 48.26) (xy 307.34 66.04)
		)
		(stroke
			(width 0)
			(type default)
		)
	)
	(wire
		(pts
			(xy 342.9 210.82) (xy 345.44 210.82)
		)
		(stroke
			(width 0)
			(type default)
		)
	)
	(bus
		(pts
			(xy 325.12 77.47) (xy 325.12 74.93)
		)
		(stroke
			(width 0)
			(type default)
		)
	)
	(bus
		(pts
			(xy 93.98 72.39) (xy 93.98 74.93)
		)
		(stroke
			(width 0)
			(type default)
		)
	)
	(wire
		(pts
			(xy 297.18 162.56) (xy 297.18 165.1)
		)
		(stroke
			(width 0)
			(type default)
		)
	)
	(wire
		(pts
			(xy 78.74 195.58) (xy 80.01 195.58)
		)
		(stroke
			(width 0)
			(type default)
		)
	)
	(wire
		(pts
			(xy 62.23 190.5) (xy 66.04 190.5)
		)
		(stroke
			(width 0)
			(type default)
		)
	)
	(wire
		(pts
			(xy 62.23 196.85) (xy 62.23 198.12)
		)
		(stroke
			(width 0)
			(type default)
		)
	)
	(wire
		(pts
			(xy 262.89 86.36) (xy 287.02 86.36)
		)
		(stroke
			(width 0)
			(type default)
		)
	)
	(wire
		(pts
			(xy 132.08 236.22) (xy 160.02 236.22)
		)
		(stroke
			(width 0)
			(type default)
		)
	)
	(wire
		(pts
			(xy 137.16 180.34) (xy 139.7 180.34)
		)
		(stroke
			(width 0)
			(type default)
		)
	)
	(wire
		(pts
			(xy 327.66 203.2) (xy 342.9 203.2)
		)
		(stroke
			(width 0)
			(type default)
		)
	)
	(wire
		(pts
			(xy 227.33 121.92) (xy 232.41 121.92)
		)
		(stroke
			(width 0)
			(type default)
		)
	)
	(wire
		(pts
			(xy 78.74 226.06) (xy 80.01 226.06)
		)
		(stroke
			(width 0)
			(type default)
		)
	)
	(wire
		(pts
			(xy 130.81 190.5) (xy 160.02 190.5)
		)
		(stroke
			(width 0)
			(type default)
		)
	)
	(wire
		(pts
			(xy 74.93 212.09) (xy 74.93 213.36)
		)
		(stroke
			(width 0)
			(type default)
		)
	)
	(wire
		(pts
			(xy 66.04 193.04) (xy 69.85 193.04)
		)
		(stroke
			(width 0)
			(type default)
		)
	)
	(wire
		(pts
			(xy 262.89 78.74) (xy 287.02 78.74)
		)
		(stroke
			(width 0)
			(type default)
		)
	)
	(wire
		(pts
			(xy 149.86 210.82) (xy 160.02 210.82)
		)
		(stroke
			(width 0)
			(type default)
		)
	)
	(wire
		(pts
			(xy 194.31 193.04) (xy 190.5 193.04)
		)
		(stroke
			(width 0)
			(type default)
		)
	)
	(wire
		(pts
			(xy 62.23 231.14) (xy 80.01 231.14)
		)
		(stroke
			(width 0)
			(type default)
		)
	)
	(wire
		(pts
			(xy 194.31 200.66) (xy 190.5 200.66)
		)
		(stroke
			(width 0)
			(type default)
		)
	)
	(wire
		(pts
			(xy 149.86 215.9) (xy 160.02 215.9)
		)
		(stroke
			(width 0)
			(type default)
		)
	)
	(wire
		(pts
			(xy 95.25 83.82) (xy 115.57 83.82)
		)
		(stroke
			(width 0)
			(type default)
		)
	)
	(wire
		(pts
			(xy 297.18 208.28) (xy 297.18 210.82)
		)
		(stroke
			(width 0)
			(type default)
		)
	)
	(bus
		(pts
			(xy 93.98 77.47) (xy 93.98 74.93)
		)
		(stroke
			(width 0)
			(type default)
		)
	)
	(wire
		(pts
			(xy 314.96 76.2) (xy 323.85 76.2)
		)
		(stroke
			(width 0)
			(type default)
		)
	)
	(wire
		(pts
			(xy 144.78 181.61) (xy 144.78 185.42)
		)
		(stroke
			(width 0)
			(type default)
		)
	)
	(wire
		(pts
			(xy 337.82 231.14) (xy 337.82 213.36)
		)
		(stroke
			(width 0)
			(type default)
		)
	)
	(wire
		(pts
			(xy 342.9 193.04) (xy 337.82 193.04)
		)
		(stroke
			(width 0)
			(type default)
		)
	)
	(wire
		(pts
			(xy 149.86 200.66) (xy 160.02 200.66)
		)
		(stroke
			(width 0)
			(type default)
		)
	)
	(wire
		(pts
			(xy 132.08 243.84) (xy 132.08 236.22)
		)
		(stroke
			(width 0)
			(type default)
		)
	)
	(bus
		(pts
			(xy 60.96 227.33) (xy 60.96 229.87)
		)
		(stroke
			(width 0)
			(type default)
		)
	)
	(wire
		(pts
			(xy 245.11 223.52) (xy 245.11 226.06)
		)
		(stroke
			(width 0)
			(type default)
		)
	)
	(wire
		(pts
			(xy 317.5 162.56) (xy 327.66 162.56)
		)
		(stroke
			(width 0)
			(type default)
		)
	)
	(wire
		(pts
			(xy 304.8 50.8) (xy 304.8 62.23)
		)
		(stroke
			(width 0)
			(type default)
		)
	)
	(wire
		(pts
			(xy 105.41 218.44) (xy 105.41 219.71)
		)
		(stroke
			(width 0)
			(type default)
		)
	)
	(wire
		(pts
			(xy 62.23 190.5) (xy 62.23 191.77)
		)
		(stroke
			(width 0)
			(type default)
		)
	)
	(wire
		(pts
			(xy 292.1 86.36) (xy 304.8 86.36)
		)
		(stroke
			(width 0)
			(type default)
		)
	)
	(wire
		(pts
			(xy 276.86 184.15) (xy 276.86 185.42)
		)
		(stroke
			(width 0)
			(type default)
		)
	)
	(bus
		(pts
			(xy 325.12 77.47) (xy 325.12 82.55)
		)
		(stroke
			(width 0)
			(type default)
		)
	)
	(wire
		(pts
			(xy 342.9 200.66) (xy 345.44 200.66)
		)
		(stroke
			(width 0)
			(type default)
		)
	)
	(wire
		(pts
			(xy 297.18 185.42) (xy 307.34 185.42)
		)
		(stroke
			(width 0)
			(type default)
		)
	)
	(wire
		(pts
			(xy 118.11 86.36) (xy 128.27 86.36)
		)
		(stroke
			(width 0)
			(type default)
		)
	)
	(wire
		(pts
			(xy 186.69 121.92) (xy 181.61 121.92)
		)
		(stroke
			(width 0)
			(type default)
		)
	)
	(wire
		(pts
			(xy 327.66 162.56) (xy 342.9 162.56)
		)
		(stroke
			(width 0)
			(type default)
		)
	)
	(wire
		(pts
			(xy 78.74 196.85) (xy 78.74 195.58)
		)
		(stroke
			(width 0)
			(type default)
		)
	)
	(wire
		(pts
			(xy 276.86 231.14) (xy 276.86 233.68)
		)
		(stroke
			(width 0)
			(type default)
		)
	)
	(wire
		(pts
			(xy 297.18 185.42) (xy 297.18 187.96)
		)
		(stroke
			(width 0)
			(type default)
		)
	)
	(wire
		(pts
			(xy 304.8 86.36) (xy 323.85 86.36)
		)
		(stroke
			(width 0)
			(type default)
		)
	)
	(wire
		(pts
			(xy 276.86 162.56) (xy 287.02 162.56)
		)
		(stroke
			(width 0)
			(type default)
		)
	)
	(wire
		(pts
			(xy 139.7 180.34) (xy 139.7 185.42)
		)
		(stroke
			(width 0)
			(type default)
		)
	)
	(wire
		(pts
			(xy 133.35 86.36) (xy 151.13 86.36)
		)
		(stroke
			(width 0)
			(type default)
		)
	)
	(wire
		(pts
			(xy 288.29 83.82) (xy 307.34 83.82)
		)
		(stroke
			(width 0)
			(type default)
		)
	)
	(wire
		(pts
			(xy 307.34 162.56) (xy 317.5 162.56)
		)
		(stroke
			(width 0)
			(type default)
		)
	)
	(wire
		(pts
			(xy 95.25 86.36) (xy 118.11 86.36)
		)
		(stroke
			(width 0)
			(type default)
		)
	)
	(wire
		(pts
			(xy 287.02 185.42) (xy 297.18 185.42)
		)
		(stroke
			(width 0)
			(type default)
		)
	)
	(wire
		(pts
			(xy 227.33 116.84) (xy 232.41 116.84)
		)
		(stroke
			(width 0)
			(type default)
		)
	)
	(bus
		(pts
			(xy 93.98 77.47) (xy 93.98 82.55)
		)
		(stroke
			(width 0)
			(type default)
		)
	)
	(bus
		(pts
			(xy 60.96 227.33) (xy 59.69 226.06)
		)
		(stroke
			(width 0)
			(type default)
		)
	)
	(wire
		(pts
			(xy 276.86 208.28) (xy 287.02 208.28)
		)
		(stroke
			(width 0)
			(type default)
		)
	)
	(wire
		(pts
			(xy 345.44 205.74) (xy 342.9 205.74)
		)
		(stroke
			(width 0)
			(type default)
		)
	)
	(wire
		(pts
			(xy 287.02 231.14) (xy 287.02 233.68)
		)
		(stroke
			(width 0)
			(type default)
		)
	)
	(wire
		(pts
			(xy 129.54 76.2) (xy 151.13 76.2)
		)
		(stroke
			(width 0)
			(type default)
		)
	)
	(wire
		(pts
			(xy 118.11 193.04) (xy 120.65 190.5)
		)
		(stroke
			(width 0)
			(type default)
		)
	)
	(wire
		(pts
			(xy 314.96 67.31) (xy 314.96 76.2)
		)
		(stroke
			(width 0)
			(type default)
		)
	)
	(wire
		(pts
			(xy 317.5 162.56) (xy 317.5 165.1)
		)
		(stroke
			(width 0)
			(type default)
		)
	)
	(wire
		(pts
			(xy 186.69 116.84) (xy 181.61 116.84)
		)
		(stroke
			(width 0)
			(type default)
		)
	)
	(wire
		(pts
			(xy 297.18 208.28) (xy 307.34 208.28)
		)
		(stroke
			(width 0)
			(type default)
		)
	)
	(wire
		(pts
			(xy 276.86 185.42) (xy 276.86 187.96)
		)
		(stroke
			(width 0)
			(type default)
		)
	)
	(wire
		(pts
			(xy 62.23 228.6) (xy 80.01 228.6)
		)
		(stroke
			(width 0)
			(type default)
		)
	)
	(wire
		(pts
			(xy 95.25 76.2) (xy 107.95 76.2)
		)
		(stroke
			(width 0)
			(type default)
		)
	)
	(wire
		(pts
			(xy 149.86 208.28) (xy 160.02 208.28)
		)
		(stroke
			(width 0)
			(type default)
		)
	)
	(wire
		(pts
			(xy 110.49 50.8) (xy 304.8 50.8)
		)
		(stroke
			(width 0)
			(type default)
		)
	)
	(wire
		(pts
			(xy 110.49 50.8) (xy 110.49 62.23)
		)
		(stroke
			(width 0)
			(type default)
		)
	)
	(wire
		(pts
			(xy 276.86 162.56) (xy 276.86 165.1)
		)
		(stroke
			(width 0)
			(type default)
		)
	)
	(bus
		(pts
			(xy 325.12 82.55) (xy 325.12 85.09)
		)
		(stroke
			(width 0)
			(type default)
		)
	)
	(wire
		(pts
			(xy 139.7 185.42) (xy 144.78 185.42)
		)
		(stroke
			(width 0)
			(type default)
		)
	)
	(wire
		(pts
			(xy 118.11 44.45) (xy 118.11 62.23)
		)
		(stroke
			(width 0)
			(type default)
		)
	)
	(wire
		(pts
			(xy 200.66 223.52) (xy 200.66 241.3)
		)
		(stroke
			(width 0)
			(type default)
		)
	)
	(wire
		(pts
			(xy 193.04 223.52) (xy 193.04 243.84)
		)
		(stroke
			(width 0)
			(type default)
		)
	)
	(wire
		(pts
			(xy 125.73 214.63) (xy 125.73 215.9)
		)
		(stroke
			(width 0)
			(type default)
		)
	)
	(wire
		(pts
			(xy 342.9 203.2) (xy 342.9 205.74)
		)
		(stroke
			(width 0)
			(type default)
		)
	)
	(bus
		(pts
			(xy 373.38 69.85) (xy 327.66 69.85)
		)
		(stroke
			(width 0)
			(type default)
		)
	)
	(wire
		(pts
			(xy 307.34 208.28) (xy 307.34 210.82)
		)
		(stroke
			(width 0)
			(type default)
		)
	)
	(wire
		(pts
			(xy 115.57 71.12) (xy 115.57 83.82)
		)
		(stroke
			(width 0)
			(type default)
		)
	)
	(wire
		(pts
			(xy 342.9 187.96) (xy 342.9 185.42)
		)
		(stroke
			(width 0)
			(type default)
		)
	)
	(wire
		(pts
			(xy 137.16 185.42) (xy 139.7 185.42)
		)
		(stroke
			(width 0)
			(type default)
		)
	)
	(wire
		(pts
			(xy 190.5 241.3) (xy 200.66 241.3)
		)
		(stroke
			(width 0)
			(type default)
		)
	)
	(wire
		(pts
			(xy 74.93 212.09) (xy 78.74 212.09)
		)
		(stroke
			(width 0)
			(type default)
		)
	)
	(wire
		(pts
			(xy 99.06 190.5) (xy 118.11 190.5)
		)
		(stroke
			(width 0)
			(type default)
		)
	)
	(wire
		(pts
			(xy 190.5 243.84) (xy 193.04 243.84)
		)
		(stroke
			(width 0)
			(type default)
		)
	)
	(wire
		(pts
			(xy 199.39 114.3) (xy 199.39 115.57)
		)
		(stroke
			(width 0)
			(type default)
		)
	)
	(wire
		(pts
			(xy 95.25 78.74) (xy 110.49 78.74)
		)
		(stroke
			(width 0)
			(type default)
		)
	)
	(wire
		(pts
			(xy 317.5 208.28) (xy 327.66 208.28)
		)
		(stroke
			(width 0)
			(type default)
		)
	)
	(bus
		(pts
			(xy 327.66 69.85) (xy 325.12 72.39)
		)
		(stroke
			(width 0)
			(type default)
		)
	)
	(wire
		(pts
			(xy 101.6 212.09) (xy 101.6 226.06)
		)
		(stroke
			(width 0)
			(type default)
		)
	)
	(wire
		(pts
			(xy 199.39 115.57) (xy 199.39 116.84)
		)
		(stroke
			(width 0)
			(type default)
		)
	)
	(wire
		(pts
			(xy 287.02 208.28) (xy 287.02 210.82)
		)
		(stroke
			(width 0)
			(type default)
		)
	)
	(wire
		(pts
			(xy 120.65 231.14) (xy 100.33 231.14)
		)
		(stroke
			(width 0)
			(type default)
		)
	)
	(wire
		(pts
			(xy 287.02 162.56) (xy 287.02 165.1)
		)
		(stroke
			(width 0)
			(type default)
		)
	)
	(wire
		(pts
			(xy 101.6 233.68) (xy 100.33 233.68)
		)
		(stroke
			(width 0)
			(type default)
		)
	)
	(wire
		(pts
			(xy 107.95 48.26) (xy 307.34 48.26)
		)
		(stroke
			(width 0)
			(type default)
		)
	)
	(wire
		(pts
			(xy 209.55 124.46) (xy 209.55 121.92)
		)
		(stroke
			(width 0)
			(type default)
		)
	)
	(wire
		(pts
			(xy 327.66 162.56) (xy 327.66 165.1)
		)
		(stroke
			(width 0)
			(type default)
		)
	)
	(wire
		(pts
			(xy 101.6 226.06) (xy 101.6 233.68)
		)
		(stroke
			(width 0)
			(type default)
		)
	)
	(wire
		(pts
			(xy 199.39 115.57) (xy 209.55 115.57)
		)
		(stroke
			(width 0)
			(type default)
		)
	)
	(wire
		(pts
			(xy 345.44 195.58) (xy 342.9 195.58)
		)
		(stroke
			(width 0)
			(type default)
		)
	)
	(wire
		(pts
			(xy 375.92 215.9) (xy 378.46 215.9)
		)
		(stroke
			(width 0)
			(type default)
		)
	)
	(wire
		(pts
			(xy 125.73 213.36) (xy 125.73 214.63)
		)
		(stroke
			(width 0)
			(type default)
		)
	)
	(wire
		(pts
			(xy 287.02 162.56) (xy 297.18 162.56)
		)
		(stroke
			(width 0)
			(type default)
		)
	)
	(wire
		(pts
			(xy 120.65 228.6) (xy 100.33 228.6)
		)
		(stroke
			(width 0)
			(type default)
		)
	)
	(wire
		(pts
			(xy 110.49 67.31) (xy 110.49 78.74)
		)
		(stroke
			(width 0)
			(type default)
		)
	)
	(wire
		(pts
			(xy 307.34 83.82) (xy 323.85 83.82)
		)
		(stroke
			(width 0)
			(type default)
		)
	)
	(wire
		(pts
			(xy 276.86 231.14) (xy 287.02 231.14)
		)
		(stroke
			(width 0)
			(type default)
		)
	)
	(wire
		(pts
			(xy 181.61 124.46) (xy 199.39 124.46)
		)
		(stroke
			(width 0)
			(type default)
		)
	)
	(wire
		(pts
			(xy 149.86 223.52) (xy 160.02 223.52)
		)
		(stroke
			(width 0)
			(type default)
		)
	)
	(wire
		(pts
			(xy 342.9 195.58) (xy 342.9 193.04)
		)
		(stroke
			(width 0)
			(type default)
		)
	)
	(wire
		(pts
			(xy 327.66 208.28) (xy 327.66 203.2)
		)
		(stroke
			(width 0)
			(type default)
		)
	)
	(wire
		(pts
			(xy 107.95 48.26) (xy 107.95 66.04)
		)
		(stroke
			(width 0)
			(type default)
		)
	)
	(wire
		(pts
			(xy 307.34 162.56) (xy 307.34 165.1)
		)
		(stroke
			(width 0)
			(type default)
		)
	)
	(wire
		(pts
			(xy 74.93 193.04) (xy 80.01 193.04)
		)
		(stroke
			(width 0)
			(type default)
		)
	)
	(wire
		(pts
			(xy 317.5 208.28) (xy 317.5 210.82)
		)
		(stroke
			(width 0)
			(type default)
		)
	)
	(wire
		(pts
			(xy 287.02 231.14) (xy 337.82 231.14)
		)
		(stroke
			(width 0)
			(type default)
		)
	)
	(wire
		(pts
			(xy 134.62 214.63) (xy 125.73 214.63)
		)
		(stroke
			(width 0)
			(type default)
		)
	)
	(wire
		(pts
			(xy 276.86 185.42) (xy 287.02 185.42)
		)
		(stroke
			(width 0)
			(type default)
		)
	)
	(wire
		(pts
			(xy 297.18 162.56) (xy 307.34 162.56)
		)
		(stroke
			(width 0)
			(type default)
		)
	)
	(wire
		(pts
			(xy 307.34 185.42) (xy 307.34 187.96)
		)
		(stroke
			(width 0)
			(type default)
		)
	)
	(wire
		(pts
			(xy 342.9 213.36) (xy 342.9 210.82)
		)
		(stroke
			(width 0)
			(type default)
		)
	)
	(wire
		(pts
			(xy 342.9 193.04) (xy 345.44 193.04)
		)
		(stroke
			(width 0)
			(type default)
		)
	)
	(wire
		(pts
			(xy 327.66 208.28) (xy 327.66 210.82)
		)
		(stroke
			(width 0)
			(type default)
		)
	)
	(wire
		(pts
			(xy 194.31 190.5) (xy 190.5 190.5)
		)
		(stroke
			(width 0)
			(type default)
		)
	)
	(wire
		(pts
			(xy 342.9 203.2) (xy 345.44 203.2)
		)
		(stroke
			(width 0)
			(type default)
		)
	)
	(bus
		(pts
			(xy 325.12 72.39) (xy 325.12 74.93)
		)
		(stroke
			(width 0)
			(type default)
		)
	)
	(wire
		(pts
			(xy 276.86 161.29) (xy 276.86 162.56)
		)
		(stroke
			(width 0)
			(type default)
		)
	)
	(wire
		(pts
			(xy 110.49 78.74) (xy 128.27 78.74)
		)
		(stroke
			(width 0)
			(type default)
		)
	)
	(wire
		(pts
			(xy 129.54 83.82) (xy 151.13 83.82)
		)
		(stroke
			(width 0)
			(type default)
		)
	)
	(wire
		(pts
			(xy 190.5 228.6) (xy 237.49 228.6)
		)
		(stroke
			(width 0)
			(type default)
		)
	)
	(wire
		(pts
			(xy 314.96 41.91) (xy 314.96 62.23)
		)
		(stroke
			(width 0)
			(type default)
		)
	)
	(wire
		(pts
			(xy 80.01 233.68) (xy 78.74 233.68)
		)
		(stroke
			(width 0)
			(type default)
		)
	)
	(wire
		(pts
			(xy 200.66 241.3) (xy 200.66 245.11)
		)
		(stroke
			(width 0)
			(type default)
		)
	)
	(wire
		(pts
			(xy 78.74 212.09) (xy 78.74 226.06)
		)
		(stroke
			(width 0)
			(type default)
		)
	)
	(wire
		(pts
			(xy 190.5 233.68) (xy 223.52 233.68)
		)
		(stroke
			(width 0)
			(type default)
		)
	)
	(wire
		(pts
			(xy 262.89 76.2) (xy 283.21 76.2)
		)
		(stroke
			(width 0)
			(type default)
		)
	)
	(wire
		(pts
			(xy 190.5 198.12) (xy 194.31 198.12)
		)
		(stroke
			(width 0)
			(type default)
		)
	)
	(wire
		(pts
			(xy 307.34 185.42) (xy 337.82 185.42)
		)
		(stroke
			(width 0)
			(type default)
		)
	)
	(wire
		(pts
			(xy 144.78 185.42) (xy 160.02 185.42)
		)
		(stroke
			(width 0)
			(type default)
		)
	)
	(wire
		(pts
			(xy 62.23 189.23) (xy 62.23 190.5)
		)
		(stroke
			(width 0)
			(type default)
		)
	)
	(wire
		(pts
			(xy 287.02 208.28) (xy 297.18 208.28)
		)
		(stroke
			(width 0)
			(type default)
		)
	)
	(wire
		(pts
			(xy 342.9 187.96) (xy 345.44 187.96)
		)
		(stroke
			(width 0)
			(type default)
		)
	)
	(wire
		(pts
			(xy 120.65 190.5) (xy 125.73 190.5)
		)
		(stroke
			(width 0)
			(type default)
		)
	)
	(wire
		(pts
			(xy 125.73 228.6) (xy 160.02 228.6)
		)
		(stroke
			(width 0)
			(type default)
		)
	)
	(wire
		(pts
			(xy 287.02 185.42) (xy 287.02 187.96)
		)
		(stroke
			(width 0)
			(type default)
		)
	)
	(wire
		(pts
			(xy 276.86 229.87) (xy 276.86 231.14)
		)
		(stroke
			(width 0)
			(type default)
		)
	)
	(wire
		(pts
			(xy 345.44 213.36) (xy 342.9 213.36)
		)
		(stroke
			(width 0)
			(type default)
		)
	)
	(bus
		(pts
			(xy 91.44 69.85) (xy 93.98 72.39)
		)
		(stroke
			(width 0)
			(type default)
		)
	)
	(wire
		(pts
			(xy 107.95 76.2) (xy 124.46 76.2)
		)
		(stroke
			(width 0)
			(type default)
		)
	)
	(wire
		(pts
			(xy 337.82 193.04) (xy 337.82 185.42)
		)
		(stroke
			(width 0)
			(type default)
		)
	)
	(wire
		(pts
			(xy 157.48 243.84) (xy 160.02 243.84)
		)
		(stroke
			(width 0)
			(type default)
		)
	)
	(wire
		(pts
			(xy 307.34 208.28) (xy 317.5 208.28)
		)
		(stroke
			(width 0)
			(type default)
		)
	)
	(wire
		(pts
			(xy 105.41 212.09) (xy 105.41 213.36)
		)
		(stroke
			(width 0)
			(type default)
		)
	)
	(wire
		(pts
			(xy 232.41 124.46) (xy 209.55 124.46)
		)
		(stroke
			(width 0)
			(type default)
		)
	)
	(wire
		(pts
			(xy 134.62 220.98) (xy 134.62 214.63)
		)
		(stroke
			(width 0)
			(type default)
		)
	)
	(wire
		(pts
			(xy 149.86 198.12) (xy 160.02 198.12)
		)
		(stroke
			(width 0)
			(type default)
		)
	)
	(wire
		(pts
			(xy 292.1 78.74) (xy 312.42 78.74)
		)
		(stroke
			(width 0)
			(type default)
		)
	)
	(wire
		(pts
			(xy 345.44 185.42) (xy 342.9 185.42)
		)
		(stroke
			(width 0)
			(type default)
		)
	)
	(wire
		(pts
			(xy 186.69 119.38) (xy 181.61 119.38)
		)
		(stroke
			(width 0)
			(type default)
		)
	)
	(wire
		(pts
			(xy 193.04 243.84) (xy 193.04 245.11)
		)
		(stroke
			(width 0)
			(type default)
		)
	)
	(wire
		(pts
			(xy 115.57 41.91) (xy 115.57 66.04)
		)
		(stroke
			(width 0)
			(type default)
		)
	)
	(wire
		(pts
			(xy 262.89 83.82) (xy 283.21 83.82)
		)
		(stroke
			(width 0)
			(type default)
		)
	)
	(wire
		(pts
			(xy 276.86 208.28) (xy 276.86 210.82)
		)
		(stroke
			(width 0)
			(type default)
		)
	)
	(wire
		(pts
			(xy 134.62 193.04) (xy 160.02 193.04)
		)
		(stroke
			(width 0)
			(type default)
		)
	)
	(wire
		(pts
			(xy 133.35 78.74) (xy 151.13 78.74)
		)
		(stroke
			(width 0)
			(type default)
		)
	)
	(wire
		(pts
			(xy 149.86 213.36) (xy 160.02 213.36)
		)
		(stroke
			(width 0)
			(type default)
		)
	)
	(wire
		(pts
			(xy 190.5 238.76) (xy 208.28 238.76)
		)
		(stroke
			(width 0)
			(type default)
		)
	)
	(wire
		(pts
			(xy 118.11 67.31) (xy 118.11 86.36)
		)
		(stroke
			(width 0)
			(type default)
		)
	)
	(wire
		(pts
			(xy 115.57 41.91) (xy 314.96 41.91)
		)
		(stroke
			(width 0)
			(type default)
		)
	)
	(wire
		(pts
			(xy 288.29 76.2) (xy 314.96 76.2)
		)
		(stroke
			(width 0)
			(type default)
		)
	)
	(wire
		(pts
			(xy 312.42 66.04) (xy 312.42 44.45)
		)
		(stroke
			(width 0)
			(type default)
		)
	)
	(wire
		(pts
			(xy 227.33 119.38) (xy 232.41 119.38)
		)
		(stroke
			(width 0)
			(type default)
		)
	)
	(wire
		(pts
			(xy 304.8 67.31) (xy 304.8 86.36)
		)
		(stroke
			(width 0)
			(type default)
		)
	)
	(wire
		(pts
			(xy 312.42 78.74) (xy 323.85 78.74)
		)
		(stroke
			(width 0)
			(type default)
		)
	)
	(wire
		(pts
			(xy 199.39 124.46) (xy 199.39 121.92)
		)
		(stroke
			(width 0)
			(type default)
		)
	)
	(bus
		(pts
			(xy 93.98 82.55) (xy 93.98 85.09)
		)
		(stroke
			(width 0)
			(type default)
		)
	)
	(wire
		(pts
			(xy 209.55 116.84) (xy 209.55 115.57)
		)
		(stroke
			(width 0)
			(type default)
		)
	)
	(wire
		(pts
			(xy 307.34 71.12) (xy 307.34 83.82)
		)
		(stroke
			(width 0)
			(type default)
		)
	)
	(wire
		(pts
			(xy 312.42 44.45) (xy 118.11 44.45)
		)
		(stroke
			(width 0)
			(type default)
		)
	)
	(bus
		(pts
			(xy 57.15 226.06) (xy 59.69 226.06)
		)
		(stroke
			(width 0)
			(type default)
		)
	)
	(wire
		(pts
			(xy 237.49 228.6) (xy 237.49 245.11)
		)
		(stroke
			(width 0)
			(type default)
		)
	)
	(wire
		(pts
			(xy 107.95 71.12) (xy 107.95 76.2)
		)
		(stroke
			(width 0)
			(type default)
		)
	)
	(wire
		(pts
			(xy 125.73 231.14) (xy 160.02 231.14)
		)
		(stroke
			(width 0)
			(type default)
		)
	)
	(wire
		(pts
			(xy 140.97 243.84) (xy 140.97 238.76)
		)
		(stroke
			(width 0)
			(type default)
		)
	)
	(wire
		(pts
			(xy 99.06 193.04) (xy 118.11 193.04)
		)
		(stroke
			(width 0)
			(type default)
		)
	)
	(wire
		(pts
			(xy 100.33 226.06) (xy 101.6 226.06)
		)
		(stroke
			(width 0)
			(type default)
		)
	)
	(wire
		(pts
			(xy 66.04 193.04) (xy 66.04 190.5)
		)
		(stroke
			(width 0)
			(type default)
		)
	)
	(wire
		(pts
			(xy 190.5 226.06) (xy 245.11 226.06)
		)
		(stroke
			(width 0)
			(type default)
		)
	)
	(wire
		(pts
			(xy 157.48 241.3) (xy 160.02 241.3)
		)
		(stroke
			(width 0)
			(type default)
		)
	)
	(wire
		(pts
			(xy 120.65 193.04) (xy 129.54 193.04)
		)
		(stroke
			(width 0)
			(type default)
		)
	)
	(wire
		(pts
			(xy 115.57 83.82) (xy 124.46 83.82)
		)
		(stroke
			(width 0)
			(type default)
		)
	)
	(wire
		(pts
			(xy 105.41 212.09) (xy 101.6 212.09)
		)
		(stroke
			(width 0)
			(type default)
		)
	)
	(label "KR.TX+"
		(at 104.14 83.82 180)
		(effects
			(font
				(size 1.27 1.27)
			)
			(justify right bottom)
		)
	)
	(label "SFI.RX+"
		(at 294.64 83.82 0)
		(effects
			(font
				(size 1.27 1.27)
			)
			(justify left bottom)
		)
	)
	(label "SFI_R.TX-"
		(at 265.43 78.74 0)
		(effects
			(font
				(size 1.27 1.27)
			)
			(justify left bottom)
		)
	)
	(label "BYP_TX-"
		(at 293.37 44.45 0)
		(effects
			(font
				(size 1.27 1.27)
			)
			(justify left bottom)
		)
	)
	(label "BYP_TX+"
		(at 128.27 41.91 0)
		(effects
			(font
				(size 1.27 1.27)
			)
			(justify left bottom)
		)
	)
	(label "MDIO.MDIO"
		(at 74.93 228.6 180)
		(effects
			(font
				(size 1.27 1.27)
			)
			(justify right bottom)
		)
	)
	(label "SFI.TX+"
		(at 294.64 76.2 0)
		(effects
			(font
				(size 1.27 1.27)
			)
			(justify left bottom)
		)
	)
	(label "BYP_RX+"
		(at 128.27 48.26 0)
		(effects
			(font
				(size 1.27 1.27)
			)
			(justify left bottom)
		)
	)
	(label "BYP_RX+"
		(at 293.37 48.26 0)
		(effects
			(font
				(size 1.27 1.27)
			)
			(justify left bottom)
		)
	)
	(label "REFCLK-"
		(at 152.4 193.04 180)
		(effects
			(font
				(size 1.27 1.27)
			)
			(justify right bottom)
		)
	)
	(label "BYP_TX-"
		(at 128.27 44.45 0)
		(effects
			(font
				(size 1.27 1.27)
			)
			(justify left bottom)
		)
	)
	(label "MDIO_R"
		(at 102.87 228.6 0)
		(effects
			(font
				(size 1.27 1.27)
			)
			(justify left bottom)
		)
	)
	(label "SFI_R.TX+"
		(at 265.43 76.2 0)
		(effects
			(font
				(size 1.27 1.27)
			)
			(justify left bottom)
		)
	)
	(label "MDC"
		(at 140.97 231.14 0)
		(effects
			(font
				(size 1.27 1.27)
			)
			(justify left bottom)
		)
	)
	(label "KR.RX+"
		(at 104.14 76.2 180)
		(effects
			(font
				(size 1.27 1.27)
			)
			(justify right bottom)
		)
	)
	(label "BYP_TX+"
		(at 293.37 41.91 0)
		(effects
			(font
				(size 1.27 1.27)
			)
			(justify left bottom)
		)
	)
	(label "KR_R.RX-"
		(at 148.59 78.74 180)
		(effects
			(font
				(size 1.27 1.27)
			)
			(justify right bottom)
		)
	)
	(label "SFI.RX-"
		(at 294.64 86.36 0)
		(effects
			(font
				(size 1.27 1.27)
			)
			(justify left bottom)
		)
	)
	(label "KR_C.TX-"
		(at 148.59 86.36 180)
		(effects
			(font
				(size 1.27 1.27)
			)
			(justify right bottom)
		)
	)
	(label "MDIO"
		(at 140.97 228.6 0)
		(effects
			(font
				(size 1.27 1.27)
			)
			(justify left bottom)
		)
	)
	(label "TMS"
		(at 153.67 210.82 0)
		(effects
			(font
				(size 1.27 1.27)
			)
			(justify left bottom)
		)
	)
	(label "~{TRST}"
		(at 153.67 215.9 0)
		(effects
			(font
				(size 1.27 1.27)
			)
			(justify left bottom)
		)
	)
	(label "MDC_R"
		(at 102.87 231.14 0)
		(effects
			(font
				(size 1.27 1.27)
			)
			(justify left bottom)
		)
	)
	(label "TDI"
		(at 153.67 205.74 0)
		(effects
			(font
				(size 1.27 1.27)
			)
			(justify left bottom)
		)
	)
	(label "TDO"
		(at 153.67 208.28 0)
		(effects
			(font
				(size 1.27 1.27)
			)
			(justify left bottom)
		)
	)
	(label "TCK"
		(at 153.67 213.36 0)
		(effects
			(font
				(size 1.27 1.27)
			)
			(justify left bottom)
		)
	)
	(label "CLK+"
		(at 107.95 190.5 180)
		(effects
			(font
				(size 1.27 1.27)
			)
			(justify right bottom)
		)
	)
	(label "SFI_R.RX-"
		(at 265.43 86.36 0)
		(effects
			(font
				(size 1.27 1.27)
			)
			(justify left bottom)
		)
	)
	(label "SFI.TX-"
		(at 294.64 78.74 0)
		(effects
			(font
				(size 1.27 1.27)
			)
			(justify left bottom)
		)
	)
	(label "KR_C.TX+"
		(at 148.59 83.82 180)
		(effects
			(font
				(size 1.27 1.27)
			)
			(justify right bottom)
		)
	)
	(label "KR.RX-"
		(at 104.14 78.74 180)
		(effects
			(font
				(size 1.27 1.27)
			)
			(justify right bottom)
		)
	)
	(label "~{RESET}"
		(at 146.05 185.42 0)
		(effects
			(font
				(size 1.27 1.27)
			)
			(justify left bottom)
		)
	)
	(label "KR.TX-"
		(at 104.14 86.36 180)
		(effects
			(font
				(size 1.27 1.27)
			)
			(justify right bottom)
		)
	)
	(label "SFI_R.RX+"
		(at 265.43 83.82 0)
		(effects
			(font
				(size 1.27 1.27)
			)
			(justify left bottom)
		)
	)
	(label "KR_R.RX+"
		(at 148.59 76.2 180)
		(effects
			(font
				(size 1.27 1.27)
			)
			(justify right bottom)
		)
	)
	(label "PRBSEN"
		(at 140.97 220.98 0)
		(effects
			(font
				(size 1.27 1.27)
			)
			(justify left bottom)
		)
	)
	(label "MDIO.MDC"
		(at 74.93 231.14 180)
		(effects
			(font
				(size 1.27 1.27)
			)
			(justify right bottom)
		)
	)
	(label "REFCLK+"
		(at 152.4 190.5 180)
		(effects
			(font
				(size 1.27 1.27)
			)
			(justify right bottom)
		)
	)
	(label "CLK-"
		(at 107.95 193.04 180)
		(effects
			(font
				(size 1.27 1.27)
			)
			(justify right bottom)
		)
	)
	(label "BYP_RX-"
		(at 293.37 50.8 0)
		(effects
			(font
				(size 1.27 1.27)
			)
			(justify left bottom)
		)
	)
	(label "BYP_RX-"
		(at 128.27 50.8 0)
		(effects
			(font
				(size 1.27 1.27)
			)
			(justify left bottom)
		)
	)
	(hierarchical_label "MDIO{MDIO}"
		(shape input)
		(at 57.15 226.06 180)
		(effects
			(font
				(size 1.27 1.27)
			)
			(justify right)
		)
	)
	(hierarchical_label "SFI{SFI}"
		(shape input)
		(at 373.38 69.85 0)
		(effects
			(font
				(size 1.27 1.27)
			)
			(justify left)
		)
	)
	(hierarchical_label "KR{10GBaseKR}"
		(shape input)
		(at 48.26 69.85 180)
		(effects
			(font
				(size 1.27 1.27)
			)
			(justify right)
		)
	)
	(hierarchical_label "PHY_RESET"
		(shape input)
		(at 123.19 182.88 180)
		(effects
			(font
				(size 1.27 1.27)
			)
			(justify right)
		)
	)
	(symbol
		(lib_id "antmicropower:GND")
		(at 200.66 250.19 0)
		(mirror y)
		(unit 1)
		(exclude_from_sim no)
		(in_bom yes)
		(on_board yes)
		(dnp no)
		(fields_autoplaced yes)
		(property "Reference" "#PWR0343"
			(at 200.66 256.54 0)
			(effects
				(font
					(size 1.27 1.27)
				)
				(justify left bottom)
				(hide yes)
			)
		)
		(property "Value" "GND"
			(at 200.66 255.27 0)
			(effects
				(font
					(size 1.27 1.27)
				)
			)
		)
		(property "Footprint" ""
			(at 200.66 250.19 0)
			(effects
				(font
					(size 1.27 1.27)
				)
				(justify left bottom)
				(hide yes)
			)
		)
		(property "Datasheet" ""
			(at 200.66 250.19 0)
			(effects
				(font
					(size 1.27 1.27)
				)
				(justify left bottom)
				(hide yes)
			)
		)
		(property "Description" ""
			(at 200.66 250.19 0)
			(effects
				(font
					(size 1.27 1.27)
				)
				(hide yes)
			)
		)
		(property "Author" "Antmicro"
			(at 191.77 257.81 0)
			(effects
				(font
					(size 1.27 1.27)
					(thickness 0.15)
				)
				(justify left bottom)
				(hide yes)
			)
		)
		(property "License" "Apache-2.0"
			(at 191.77 260.35 0)
			(effects
				(font
					(size 1.27 1.27)
					(thickness 0.15)
				)
				(justify left bottom)
				(hide yes)
			)
		)
		(pin "1"
		)
		(instances
			(project "com-express-7-baseboard"
				(path ""
					(reference "#PWR0394")
					(unit 1)
				)
				(path ""
					(reference "#PWR0343")
					(unit 1)
				)
			)
		)
	)
	(symbol
		(lib_id "antmicropower:GND")
		(at 297.18 193.04 0)
		(mirror y)
		(unit 1)
		(exclude_from_sim no)
		(in_bom yes)
		(on_board yes)
		(dnp no)
		(fields_autoplaced yes)
		(property "Reference" "#PWR0368"
			(at 297.18 199.39 0)
			(effects
				(font
					(size 1.27 1.27)
				)
				(justify left bottom)
				(hide yes)
			)
		)
		(property "Value" "GND"
			(at 297.18 198.12 0)
			(effects
				(font
					(size 1.27 1.27)
				)
			)
		)
		(property "Footprint" ""
			(at 297.18 193.04 0)
			(effects
				(font
					(size 1.27 1.27)
				)
				(justify left bottom)
				(hide yes)
			)
		)
		(property "Datasheet" ""
			(at 297.18 193.04 0)
			(effects
				(font
					(size 1.27 1.27)
				)
				(justify left bottom)
				(hide yes)
			)
		)
		(property "Description" ""
			(at 297.18 193.04 0)
			(effects
				(font
					(size 1.27 1.27)
				)
				(hide yes)
			)
		)
		(property "Author" "Antmicro"
			(at 288.29 200.66 0)
			(effects
				(font
					(size 1.27 1.27)
					(thickness 0.15)
				)
				(justify left bottom)
				(hide yes)
			)
		)
		(property "License" "Apache-2.0"
			(at 288.29 203.2 0)
			(effects
				(font
					(size 1.27 1.27)
					(thickness 0.15)
				)
				(justify left bottom)
				(hide yes)
			)
		)
		(pin "1"
		)
		(instances
			(project "com-express-7-baseboard"
				(path ""
					(reference "#PWR0419")
					(unit 1)
				)
				(path ""
					(reference "#PWR0368")
					(unit 1)
				)
			)
		)
	)
	(symbol
		(lib_id "antmicropower:GND")
		(at 378.46 218.44 0)
		(mirror y)
		(unit 1)
		(exclude_from_sim no)
		(in_bom yes)
		(on_board yes)
		(dnp no)
		(fields_autoplaced yes)
		(property "Reference" "#PWR0377"
			(at 378.46 224.79 0)
			(effects
				(font
					(size 1.27 1.27)
				)
				(justify left bottom)
				(hide yes)
			)
		)
		(property "Value" "GND"
			(at 378.46 223.52 0)
			(effects
				(font
					(size 1.27 1.27)
				)
			)
		)
		(property "Footprint" ""
			(at 378.46 218.44 0)
			(effects
				(font
					(size 1.27 1.27)
				)
				(justify left bottom)
				(hide yes)
			)
		)
		(property "Datasheet" ""
			(at 378.46 218.44 0)
			(effects
				(font
					(size 1.27 1.27)
				)
				(justify left bottom)
				(hide yes)
			)
		)
		(property "Description" ""
			(at 378.46 218.44 0)
			(effects
				(font
					(size 1.27 1.27)
				)
				(hide yes)
			)
		)
		(property "Author" "Antmicro"
			(at 369.57 226.06 0)
			(effects
				(font
					(size 1.27 1.27)
					(thickness 0.15)
				)
				(justify left bottom)
				(hide yes)
			)
		)
		(property "License" "Apache-2.0"
			(at 369.57 228.6 0)
			(effects
				(font
					(size 1.27 1.27)
					(thickness 0.15)
				)
				(justify left bottom)
				(hide yes)
			)
		)
		(pin "1"
		)
		(instances
			(project "com-express-7-baseboard"
				(path ""
					(reference "#PWR0428")
					(unit 1)
				)
				(path ""
					(reference "#PWR0377")
					(unit 1)
				)
			)
		)
	)
	(symbol
		(lib_id "antmicropower:GND")
		(at 125.73 220.98 0)
		(mirror y)
		(unit 1)
		(exclude_from_sim no)
		(in_bom yes)
		(on_board yes)
		(dnp no)
		(property "Reference" "#PWR0336"
			(at 116.84 223.52 0)
			(effects
				(font
					(size 1.27 1.27)
					(thickness 0.15)
				)
				(justify left bottom)
				(hide yes)
			)
		)
		(property "Value" "GND"
			(at 125.73 224.79 0)
			(effects
				(font
					(size 1.27 1.27)
					(thickness 0.15)
				)
			)
		)
		(property "Footprint" ""
			(at 116.84 228.6 0)
			(effects
				(font
					(size 1.27 1.27)
					(thickness 0.15)
				)
				(justify left bottom)
				(hide yes)
			)
		)
		(property "Datasheet" ""
			(at 116.84 233.68 0)
			(effects
				(font
					(size 1.27 1.27)
					(thickness 0.15)
				)
				(justify left bottom)
				(hide yes)
			)
		)
		(property "Description" ""
			(at 125.73 220.98 0)
			(effects
				(font
					(size 1.27 1.27)
				)
				(hide yes)
			)
		)
		(property "Author" "Antmicro"
			(at 116.84 228.6 0)
			(effects
				(font
					(size 1.27 1.27)
					(thickness 0.15)
				)
				(justify left bottom)
				(hide yes)
			)
		)
		(property "License" "Apache-2.0"
			(at 116.84 231.14 0)
			(effects
				(font
					(size 1.27 1.27)
					(thickness 0.15)
				)
				(justify left bottom)
				(hide yes)
			)
		)
		(pin "1"
		)
		(instances
			(project "com-express-7-baseboard"
				(path ""
					(reference "#PWR0387")
					(unit 1)
				)
				(path ""
					(reference "#PWR0336")
					(unit 1)
				)
			)
		)
	)
	(symbol
		(lib_id "antmicroTestPoints:TP_0.75mm_SMD")
		(at 227.33 121.92 0)
		(mirror y)
		(unit 1)
		(exclude_from_sim no)
		(in_bom no)
		(on_board yes)
		(dnp no)
		(fields_autoplaced yes)
		(property "Reference" "TP76"
			(at 222.25 121.92 0)
			(effects
				(font
					(size 1.27 1.27)
					(thickness 0.15)
				)
				(justify left)
			)
		)
		(property "Value" "TP_0.75mm_SMD"
			(at 216.535 125.73 0)
			(effects
				(font
					(size 1.27 1.27)
					(thickness 0.15)
				)
				(justify left bottom)
				(hide yes)
			)
		)
		(property "Footprint" "antmicro-footprints:TP_SMD_0.75mm"
			(at 216.535 128.27 0)
			(effects
				(font
					(size 1.27 1.27)
					(thickness 0.15)
				)
				(justify left bottom)
				(hide yes)
			)
		)
		(property "Datasheet" ""
			(at 209.55 134.62 0)
			(effects
				(font
					(size 1.27 1.27)
					(thickness 0.15)
				)
				(justify left bottom)
				(hide yes)
			)
		)
		(property "Description" ""
			(at 227.33 121.92 0)
			(effects
				(font
					(size 1.27 1.27)
				)
				(hide yes)
			)
		)
		(property "MPN" ""
			(at 216.535 133.35 0)
			(effects
				(font
					(size 1.27 1.27)
					(thickness 0.15)
				)
				(justify left bottom)
				(hide yes)
			)
		)
		(property "Manufacturer" ""
			(at 216.535 128.27 0)
			(effects
				(font
					(size 1.27 1.27)
					(thickness 0.15)
				)
				(justify left bottom)
				(hide yes)
			)
		)
		(property "Author" "Antmicro"
			(at 216.535 130.81 0)
			(effects
				(font
					(size 1.27 1.27)
					(thickness 0.15)
				)
				(justify left bottom)
				(hide yes)
			)
		)
		(property "License" "Apache-2.0"
			(at 216.535 133.35 0)
			(effects
				(font
					(size 1.27 1.27)
					(thickness 0.15)
				)
				(justify left bottom)
				(hide yes)
			)
		)
		(property "Public" "False"
			(at 217.17 135.89 0)
			(effects
				(font
					(size 1.27 1.27)
				)
				(justify left bottom)
				(hide yes)
			)
		)
		(pin "1"
		)
		(instances
			(project "com-express-7-baseboard"
				(path ""
					(reference "TP96")
					(unit 1)
				)
				(path ""
					(reference "TP76")
					(unit 1)
				)
			)
		)
	)
	(symbol
		(lib_id "antmicroResistors0402:R_0R_0402")
		(at 120.65 231.14 0)
		(unit 1)
		(exclude_from_sim no)
		(in_bom yes)
		(on_board yes)
		(dnp no)
		(property "Reference" "R248"
			(at 116.84 229.87 0)
			(effects
				(font
					(size 1.27 1.27)
					(thickness 0.15)
				)
			)
		)
		(property "Value" "R_0R_0402"
			(at 140.97 243.84 0)
			(effects
				(font
					(size 1.27 1.27)
					(thickness 0.15)
				)
				(justify left bottom)
				(hide yes)
			)
		)
		(property "Footprint" "antmicro-footprints:R_0402_1005Metric"
			(at 140.97 246.38 0)
			(effects
				(font
					(size 1.27 1.27)
					(thickness 0.15)
				)
				(justify left bottom)
				(hide yes)
			)
		)
		(property "Datasheet" "https://industrial.panasonic.com/cdbs/www-data/pdf/RDA0000/AOA0000C301.pdf"
			(at 140.97 248.92 0)
			(effects
				(font
					(size 1.27 1.27)
					(thickness 0.15)
				)
				(justify left bottom)
				(hide yes)
			)
		)
		(property "Description" ""
			(at 120.65 231.14 0)
			(effects
				(font
					(size 1.27 1.27)
				)
				(hide yes)
			)
		)
		(property "MPN" "ERJ2GE0R00X"
			(at 140.97 251.46 0)
			(effects
				(font
					(size 1.27 1.27)
					(thickness 0.15)
				)
				(justify left bottom)
				(hide yes)
			)
		)
		(property "Manufacturer" "Panasonic"
			(at 140.97 254 0)
			(effects
				(font
					(size 1.27 1.27)
					(thickness 0.15)
				)
				(justify left bottom)
				(hide yes)
			)
		)
		(property "License" "Apache-2.0"
			(at 140.97 256.54 0)
			(effects
				(font
					(size 1.27 1.27)
					(thickness 0.15)
				)
				(justify left bottom)
				(hide yes)
			)
		)
		(property "Author" "Antmicro"
			(at 140.97 259.08 0)
			(effects
				(font
					(size 1.27 1.27)
					(thickness 0.15)
				)
				(justify left bottom)
				(hide yes)
			)
		)
		(property "Val" "0R"
			(at 127 229.87 0)
			(effects
				(font
					(size 1.27 1.27)
					(thickness 0.15)
				)
			)
		)
		(property "Tolerance" "~"
			(at 140.97 241.3 0)
			(effects
				(font
					(size 1.27 1.27)
				)
				(justify left bottom)
				(hide yes)
			)
		)
		(property "Current" "1A"
			(at 140.97 261.62 0)
			(effects
				(font
					(size 1.27 1.27)
					(thickness 0.15)
				)
				(justify left bottom)
				(hide yes)
			)
		)
		(property "Public" "False"
			(at 140.97 261.62 0)
			(effects
				(font
					(size 1.27 1.27)
				)
				(justify left bottom)
				(hide yes)
			)
		)
		(pin "1"
		)
		(pin "2"
		)
		(instances
			(project "com-express-7-baseboard"
				(path ""
					(reference "R282")
					(unit 1)
				)
				(path ""
					(reference "R248")
					(unit 1)
				)
			)
		)
	)
	(symbol
		(lib_id "antmicroDiodesRectifiersSingle:BAT54C")
		(at 137.16 185.42 180)
		(unit 1)
		(exclude_from_sim no)
		(in_bom yes)
		(on_board yes)
		(dnp no)
		(fields_autoplaced yes)
		(property "Reference" "D22"
			(at 130.81 173.99 0)
			(effects
				(font
					(size 1.27 1.27)
					(thickness 0.15)
				)
			)
		)
		(property "Value" "BAT54C"
			(at 114.3 176.53 0)
			(effects
				(font
					(size 1.27 1.27)
					(thickness 0.15)
				)
				(justify left bottom)
				(hide yes)
			)
		)
		(property "Footprint" "antmicro-footprints:SOT-23-3"
			(at 114.3 173.99 0)
			(effects
				(font
					(size 1.27 1.27)
					(thickness 0.15)
				)
				(justify left bottom)
				(hide yes)
			)
		)
		(property "Datasheet" "https://diotec.com/request/datasheet/bat54.pdf"
			(at 114.3 171.45 0)
			(effects
				(font
					(size 1.27 1.27)
					(thickness 0.15)
				)
				(justify left bottom)
				(hide yes)
			)
		)
		(property "Description" ""
			(at 137.16 185.42 0)
			(effects
				(font
					(size 1.27 1.27)
				)
				(hide yes)
			)
		)
		(property "MPN" "BAT54C"
			(at 130.81 176.53 0)
			(effects
				(font
					(size 1.27 1.27)
					(thickness 0.15)
				)
			)
		)
		(property "Manufacturer" "Diotec Semiconductor"
			(at 114.3 168.91 0)
			(effects
				(font
					(size 1.27 1.27)
					(thickness 0.15)
				)
				(justify left bottom)
				(hide yes)
			)
		)
		(property "Author" "Antmicro"
			(at 114.3 166.37 0)
			(effects
				(font
					(size 1.27 1.27)
					(thickness 0.15)
				)
				(justify left bottom)
				(hide yes)
			)
		)
		(property "License" "Apache-2.0"
			(at 114.3 163.83 0)
			(effects
				(font
					(size 1.27 1.27)
					(thickness 0.15)
				)
				(justify left bottom)
				(hide yes)
			)
		)
		(pin "3"
		)
		(pin "1"
		)
		(pin "2"
		)
		(instances
			(project "com-express-7-baseboard"
				(path ""
					(reference "D23")
					(unit 1)
				)
				(path ""
					(reference "D22")
					(unit 1)
				)
			)
		)
	)
	(symbol
		(lib_id "antmicropower:GND")
		(at 287.02 215.9 0)
		(mirror y)
		(unit 1)
		(exclude_from_sim no)
		(in_bom yes)
		(on_board yes)
		(dnp no)
		(fields_autoplaced yes)
		(property "Reference" "#PWR0365"
			(at 287.02 222.25 0)
			(effects
				(font
					(size 1.27 1.27)
				)
				(justify left bottom)
				(hide yes)
			)
		)
		(property "Value" "GND"
			(at 287.02 220.98 0)
			(effects
				(font
					(size 1.27 1.27)
				)
			)
		)
		(property "Footprint" ""
			(at 287.02 215.9 0)
			(effects
				(font
					(size 1.27 1.27)
				)
				(justify left bottom)
				(hide yes)
			)
		)
		(property "Datasheet" ""
			(at 287.02 215.9 0)
			(effects
				(font
					(size 1.27 1.27)
				)
				(justify left bottom)
				(hide yes)
			)
		)
		(property "Description" ""
			(at 287.02 215.9 0)
			(effects
				(font
					(size 1.27 1.27)
				)
				(hide yes)
			)
		)
		(property "Author" "Antmicro"
			(at 278.13 223.52 0)
			(effects
				(font
					(size 1.27 1.27)
					(thickness 0.15)
				)
				(justify left bottom)
				(hide yes)
			)
		)
		(property "License" "Apache-2.0"
			(at 278.13 226.06 0)
			(effects
				(font
					(size 1.27 1.27)
					(thickness 0.15)
				)
				(justify left bottom)
				(hide yes)
			)
		)
		(pin "1"
		)
		(instances
			(project "com-express-7-baseboard"
				(path ""
					(reference "#PWR0416")
					(unit 1)
				)
				(path ""
					(reference "#PWR0365")
					(unit 1)
				)
			)
		)
	)
	(symbol
		(lib_id "antmicroCapacitors0402:C_100n_0402")
		(at 276.86 170.18 90)
		(unit 1)
		(exclude_from_sim no)
		(in_bom yes)
		(on_board yes)
		(dnp no)
		(fields_autoplaced yes)
		(property "Reference" "C157"
			(at 279.4 166.3636 90)
			(effects
				(font
					(size 1.27 1.27)
					(thickness 0.15)
				)
				(justify right)
			)
		)
		(property "Value" "C_100n_0402"
			(at 287.02 149.86 0)
			(effects
				(font
					(size 1.27 1.27)
					(thickness 0.15)
				)
				(justify left bottom)
				(hide yes)
			)
		)
		(property "Footprint" "antmicro-footprints:C_0402_1005Metric"
			(at 289.56 149.86 0)
			(effects
				(font
					(size 1.27 1.27)
					(thickness 0.15)
				)
				(justify left bottom)
				(hide yes)
			)
		)
		(property "Datasheet" "https://www.murata.com/products/productdetail?partno=GRM155R61H104KE14%23"
			(at 292.1 149.86 0)
			(effects
				(font
					(size 1.27 1.27)
					(thickness 0.15)
				)
				(justify left bottom)
				(hide yes)
			)
		)
		(property "Description" ""
			(at 276.86 170.18 0)
			(effects
				(font
					(size 1.27 1.27)
				)
				(hide yes)
			)
		)
		(property "MPN" "GRM155R61H104KE14D"
			(at 294.64 149.86 0)
			(effects
				(font
					(size 1.27 1.27)
					(thickness 0.15)
				)
				(justify left bottom)
				(hide yes)
			)
		)
		(property "Manufacturer" "Murata"
			(at 297.18 149.86 0)
			(effects
				(font
					(size 1.27 1.27)
					(thickness 0.15)
				)
				(justify left bottom)
				(hide yes)
			)
		)
		(property "License" "Apache-2.0"
			(at 299.72 149.86 0)
			(effects
				(font
					(size 1.27 1.27)
					(thickness 0.15)
				)
				(justify left bottom)
				(hide yes)
			)
		)
		(property "Author" "Antmicro"
			(at 302.26 149.86 0)
			(effects
				(font
					(size 1.27 1.27)
					(thickness 0.15)
				)
				(justify left bottom)
				(hide yes)
			)
		)
		(property "Val" "100n"
			(at 279.4 168.9036 90)
			(effects
				(font
					(size 1.27 1.27)
					(thickness 0.15)
				)
				(justify right)
			)
		)
		(property "Voltage" "50V"
			(at 304.8 149.86 0)
			(effects
				(font
					(size 1.27 1.27)
				)
				(justify left bottom)
				(hide yes)
			)
		)
		(property "Dielectric" "X5R"
			(at 307.34 149.86 0)
			(effects
				(font
					(size 1.27 1.27)
				)
				(justify left bottom)
				(hide yes)
			)
		)
		(property "Public" "False"
			(at 309.88 149.86 0)
			(effects
				(font
					(size 1.27 1.27)
				)
				(justify left bottom)
				(hide yes)
			)
		)
		(pin "2"
		)
		(pin "1"
		)
		(instances
			(project "com-express-7-baseboard"
				(path ""
					(reference "C184")
					(unit 1)
				)
				(path ""
					(reference "C157")
					(unit 1)
				)
			)
		)
	)
	(symbol
		(lib_id "antmicropower:+1V8")
		(at 245.11 218.44 0)
		(unit 1)
		(exclude_from_sim no)
		(in_bom yes)
		(on_board yes)
		(dnp no)
		(property "Reference" "#PWR0349"
			(at 260.35 220.98 0)
			(effects
				(font
					(size 1.27 1.27)
					(thickness 0.15)
				)
				(justify left bottom)
				(hide yes)
			)
		)
		(property "Value" "+1V8"
			(at 245.11 214.63 0)
			(effects
				(font
					(size 1.27 1.27)
					(thickness 0.15)
				)
			)
		)
		(property "Footprint" ""
			(at 260.35 226.06 0)
			(effects
				(font
					(size 1.27 1.27)
					(thickness 0.15)
				)
				(justify left bottom)
				(hide yes)
			)
		)
		(property "Datasheet" ""
			(at 260.35 228.6 0)
			(effects
				(font
					(size 1.27 1.27)
					(thickness 0.15)
				)
				(justify left bottom)
				(hide yes)
			)
		)
		(property "Description" ""
			(at 245.11 218.44 0)
			(effects
				(font
					(size 1.27 1.27)
				)
				(hide yes)
			)
		)
		(property "Author" "Antmicro"
			(at 260.35 223.52 0)
			(effects
				(font
					(size 1.27 1.27)
					(thickness 0.15)
				)
				(justify left bottom)
				(hide yes)
			)
		)
		(property "License" "Apache-2.0"
			(at 260.35 226.06 0)
			(effects
				(font
					(size 1.27 1.27)
					(thickness 0.15)
				)
				(justify left bottom)
				(hide yes)
			)
		)
		(pin "1"
		)
		(instances
			(project "com-express-7-baseboard"
				(path ""
					(reference "#PWR0400")
					(unit 1)
				)
				(path ""
					(reference "#PWR0349")
					(unit 1)
				)
			)
		)
	)
	(symbol
		(lib_id "antmicroResistorsmisc:R_0R_0201")
		(at 304.8 67.31 90)
		(unit 1)
		(exclude_from_sim no)
		(in_bom yes)
		(on_board yes)
		(dnp yes)
		(property "Reference" "R276"
			(at 303.53 59.69 0)
			(effects
				(font
					(size 1.27 1.27)
					(thickness 0.15)
				)
			)
		)
		(property "Value" "R_0R_0201"
			(at 317.5 46.99 0)
			(effects
				(font
					(size 1.27 1.27)
					(thickness 0.15)
				)
				(justify left bottom)
				(hide yes)
			)
		)
		(property "Footprint" "antmicro-footprints:R_0201"
			(at 320.04 46.99 0)
			(effects
				(font
					(size 1.27 1.27)
					(thickness 0.15)
				)
				(justify left bottom)
				(hide yes)
			)
		)
		(property "Datasheet" "https://www.bourns.com/docs/product-datasheets/cr.pdf"
			(at 322.58 46.99 0)
			(effects
				(font
					(size 1.27 1.27)
					(thickness 0.15)
				)
				(justify left bottom)
				(hide yes)
			)
		)
		(property "Description" ""
			(at 304.8 67.31 0)
			(effects
				(font
					(size 1.27 1.27)
				)
				(hide yes)
			)
		)
		(property "MPN" "CR0201-FX-0R00GLF"
			(at 325.12 46.99 0)
			(effects
				(font
					(size 1.27 1.27)
					(thickness 0.15)
				)
				(justify left bottom)
				(hide yes)
			)
		)
		(property "Manufacturer" "Bourns"
			(at 327.66 46.99 0)
			(effects
				(font
					(size 1.27 1.27)
					(thickness 0.15)
				)
				(justify left bottom)
				(hide yes)
			)
		)
		(property "License" "Apache-2.0"
			(at 330.2 46.99 0)
			(effects
				(font
					(size 1.27 1.27)
					(thickness 0.15)
				)
				(justify left bottom)
				(hide yes)
			)
		)
		(property "Author" "Antmicro"
			(at 332.74 46.99 0)
			(effects
				(font
					(size 1.27 1.27)
					(thickness 0.15)
				)
				(justify left bottom)
				(hide yes)
			)
		)
		(property "Val" "0R"
			(at 303.53 68.58 0)
			(effects
				(font
					(size 1.27 1.27)
					(thickness 0.15)
				)
			)
		)
		(property "Tolerance" "1%"
			(at 314.96 46.99 0)
			(effects
				(font
					(size 1.27 1.27)
				)
				(justify left bottom)
				(hide yes)
			)
		)
		(pin "1"
		)
		(pin "2"
		)
		(instances
			(project "com-express-7-baseboard"
				(path ""
					(reference "R310")
					(unit 1)
				)
				(path ""
					(reference "R276")
					(unit 1)
				)
			)
		)
	)
	(symbol
		(lib_id "antmicropower:GND")
		(at 237.49 250.19 0)
		(mirror y)
		(unit 1)
		(exclude_from_sim no)
		(in_bom yes)
		(on_board yes)
		(dnp no)
		(fields_autoplaced yes)
		(property "Reference" "#PWR0348"
			(at 237.49 256.54 0)
			(effects
				(font
					(size 1.27 1.27)
				)
				(justify left bottom)
				(hide yes)
			)
		)
		(property "Value" "GND"
			(at 237.49 255.27 0)
			(effects
				(font
					(size 1.27 1.27)
				)
			)
		)
		(property "Footprint" ""
			(at 237.49 250.19 0)
			(effects
				(font
					(size 1.27 1.27)
				)
				(justify left bottom)
				(hide yes)
			)
		)
		(property "Datasheet" ""
			(at 237.49 250.19 0)
			(effects
				(font
					(size 1.27 1.27)
				)
				(justify left bottom)
				(hide yes)
			)
		)
		(property "Description" ""
			(at 237.49 250.19 0)
			(effects
				(font
					(size 1.27 1.27)
				)
				(hide yes)
			)
		)
		(property "Author" "Antmicro"
			(at 228.6 257.81 0)
			(effects
				(font
					(size 1.27 1.27)
					(thickness 0.15)
				)
				(justify left bottom)
				(hide yes)
			)
		)
		(property "License" "Apache-2.0"
			(at 228.6 260.35 0)
			(effects
				(font
					(size 1.27 1.27)
					(thickness 0.15)
				)
				(justify left bottom)
				(hide yes)
			)
		)
		(pin "1"
		)
		(instances
			(project "com-express-7-baseboard"
				(path ""
					(reference "#PWR0399")
					(unit 1)
				)
				(path ""
					(reference "#PWR0348")
					(unit 1)
				)
			)
		)
	)
	(symbol
		(lib_id "antmicroResistorsmisc:R_0R_0201")
		(at 115.57 71.12 90)
		(unit 1)
		(exclude_from_sim no)
		(in_bom yes)
		(on_board yes)
		(dnp yes)
		(property "Reference" "R251"
			(at 114.3 63.5 0)
			(effects
				(font
					(size 1.27 1.27)
					(thickness 0.15)
				)
			)
		)
		(property "Value" "R_0R_0201"
			(at 128.27 50.8 0)
			(effects
				(font
					(size 1.27 1.27)
					(thickness 0.15)
				)
				(justify left bottom)
				(hide yes)
			)
		)
		(property "Footprint" "antmicro-footprints:R_0201"
			(at 130.81 50.8 0)
			(effects
				(font
					(size 1.27 1.27)
					(thickness 0.15)
				)
				(justify left bottom)
				(hide yes)
			)
		)
		(property "Datasheet" "https://www.bourns.com/docs/product-datasheets/cr.pdf"
			(at 133.35 50.8 0)
			(effects
				(font
					(size 1.27 1.27)
					(thickness 0.15)
				)
				(justify left bottom)
				(hide yes)
			)
		)
		(property "Description" ""
			(at 115.57 71.12 0)
			(effects
				(font
					(size 1.27 1.27)
				)
				(hide yes)
			)
		)
		(property "MPN" "CR0201-FX-0R00GLF"
			(at 135.89 50.8 0)
			(effects
				(font
					(size 1.27 1.27)
					(thickness 0.15)
				)
				(justify left bottom)
				(hide yes)
			)
		)
		(property "Manufacturer" "Bourns"
			(at 138.43 50.8 0)
			(effects
				(font
					(size 1.27 1.27)
					(thickness 0.15)
				)
				(justify left bottom)
				(hide yes)
			)
		)
		(property "License" "Apache-2.0"
			(at 140.97 50.8 0)
			(effects
				(font
					(size 1.27 1.27)
					(thickness 0.15)
				)
				(justify left bottom)
				(hide yes)
			)
		)
		(property "Author" "Antmicro"
			(at 143.51 50.8 0)
			(effects
				(font
					(size 1.27 1.27)
					(thickness 0.15)
				)
				(justify left bottom)
				(hide yes)
			)
		)
		(property "Val" "0R"
			(at 114.3 72.39 0)
			(effects
				(font
					(size 1.27 1.27)
					(thickness 0.15)
				)
			)
		)
		(property "Tolerance" "1%"
			(at 125.73 50.8 0)
			(effects
				(font
					(size 1.27 1.27)
				)
				(justify left bottom)
				(hide yes)
			)
		)
		(pin "1"
		)
		(pin "2"
		)
		(instances
			(project "com-express-7-baseboard"
				(path ""
					(reference "R285")
					(unit 1)
				)
				(path ""
					(reference "R251")
					(unit 1)
				)
			)
		)
	)
	(symbol
		(lib_id "antmicroCapacitors0402:C_100n_0402")
		(at 287.02 193.04 90)
		(unit 1)
		(exclude_from_sim no)
		(in_bom yes)
		(on_board yes)
		(dnp no)
		(fields_autoplaced yes)
		(property "Reference" "C162"
			(at 289.56 189.2236 90)
			(effects
				(font
					(size 1.27 1.27)
					(thickness 0.15)
				)
				(justify right)
			)
		)
		(property "Value" "C_100n_0402"
			(at 297.18 172.72 0)
			(effects
				(font
					(size 1.27 1.27)
					(thickness 0.15)
				)
				(justify left bottom)
				(hide yes)
			)
		)
		(property "Footprint" "antmicro-footprints:C_0402_1005Metric"
			(at 299.72 172.72 0)
			(effects
				(font
					(size 1.27 1.27)
					(thickness 0.15)
				)
				(justify left bottom)
				(hide yes)
			)
		)
		(property "Datasheet" "https://www.murata.com/products/productdetail?partno=GRM155R61H104KE14%23"
			(at 302.26 172.72 0)
			(effects
				(font
					(size 1.27 1.27)
					(thickness 0.15)
				)
				(justify left bottom)
				(hide yes)
			)
		)
		(property "Description" ""
			(at 287.02 193.04 0)
			(effects
				(font
					(size 1.27 1.27)
				)
				(hide yes)
			)
		)
		(property "MPN" "GRM155R61H104KE14D"
			(at 304.8 172.72 0)
			(effects
				(font
					(size 1.27 1.27)
					(thickness 0.15)
				)
				(justify left bottom)
				(hide yes)
			)
		)
		(property "Manufacturer" "Murata"
			(at 307.34 172.72 0)
			(effects
				(font
					(size 1.27 1.27)
					(thickness 0.15)
				)
				(justify left bottom)
				(hide yes)
			)
		)
		(property "License" "Apache-2.0"
			(at 309.88 172.72 0)
			(effects
				(font
					(size 1.27 1.27)
					(thickness 0.15)
				)
				(justify left bottom)
				(hide yes)
			)
		)
		(property "Author" "Antmicro"
			(at 312.42 172.72 0)
			(effects
				(font
					(size 1.27 1.27)
					(thickness 0.15)
				)
				(justify left bottom)
				(hide yes)
			)
		)
		(property "Val" "100n"
			(at 289.56 191.7636 90)
			(effects
				(font
					(size 1.27 1.27)
					(thickness 0.15)
				)
				(justify right)
			)
		)
		(property "Voltage" "50V"
			(at 314.96 172.72 0)
			(effects
				(font
					(size 1.27 1.27)
				)
				(justify left bottom)
				(hide yes)
			)
		)
		(property "Dielectric" "X5R"
			(at 317.5 172.72 0)
			(effects
				(font
					(size 1.27 1.27)
				)
				(justify left bottom)
				(hide yes)
			)
		)
		(property "Public" "False"
			(at 320.04 172.72 0)
			(effects
				(font
					(size 1.27 1.27)
				)
				(justify left bottom)
				(hide yes)
			)
		)
		(pin "2"
		)
		(pin "1"
		)
		(instances
			(project "com-express-7-baseboard"
				(path ""
					(reference "C189")
					(unit 1)
				)
				(path ""
					(reference "C162")
					(unit 1)
				)
			)
		)
	)
	(symbol
		(lib_id "antmicroResistors0402:R_10k_0402")
		(at 200.66 223.52 90)
		(unit 1)
		(exclude_from_sim no)
		(in_bom yes)
		(on_board yes)
		(dnp yes)
		(property "Reference" "R262"
			(at 201.93 218.44 90)
			(effects
				(font
					(size 1.27 1.27)
					(thickness 0.15)
				)
				(justify right)
			)
		)
		(property "Value" "R_10k_0402"
			(at 213.36 203.2 0)
			(effects
				(font
					(size 1.27 1.27)
					(thickness 0.15)
				)
				(justify left bottom)
				(hide yes)
			)
		)
		(property "Footprint" "antmicro-footprints:R_0402_1005Metric"
			(at 215.9 203.2 0)
			(effects
				(font
					(size 1.27 1.27)
					(thickness 0.15)
				)
				(justify left bottom)
				(hide yes)
			)
		)
		(property "Datasheet" "https://www.bourns.com/docs/product-datasheets/cr.pdf"
			(at 218.44 203.2 0)
			(effects
				(font
					(size 1.27 1.27)
					(thickness 0.15)
				)
				(justify left bottom)
				(hide yes)
			)
		)
		(property "Description" ""
			(at 200.66 223.52 0)
			(effects
				(font
					(size 1.27 1.27)
				)
				(hide yes)
			)
		)
		(property "MPN" "CR0402-FX-1002GLF"
			(at 220.98 203.2 0)
			(effects
				(font
					(size 1.27 1.27)
					(thickness 0.15)
				)
				(justify left bottom)
				(hide yes)
			)
		)
		(property "Manufacturer" "Bourns"
			(at 223.52 203.2 0)
			(effects
				(font
					(size 1.27 1.27)
					(thickness 0.15)
				)
				(justify left bottom)
				(hide yes)
			)
		)
		(property "License" "Apache-2.0"
			(at 226.06 203.2 0)
			(effects
				(font
					(size 1.27 1.27)
					(thickness 0.15)
				)
				(justify left bottom)
				(hide yes)
			)
		)
		(property "Author" "Antmicro"
			(at 228.6 203.2 0)
			(effects
				(font
					(size 1.27 1.27)
					(thickness 0.15)
				)
				(justify left bottom)
				(hide yes)
			)
		)
		(property "Val" "10k"
			(at 201.93 220.98 90)
			(effects
				(font
					(size 1.27 1.27)
					(thickness 0.15)
				)
				(justify right)
			)
		)
		(property "Tolerance" "1%"
			(at 210.82 203.2 0)
			(effects
				(font
					(size 1.27 1.27)
				)
				(justify left bottom)
				(hide yes)
			)
		)
		(property "Public" "False"
			(at 231.14 203.2 0)
			(effects
				(font
					(size 1.27 1.27)
				)
				(justify left bottom)
				(hide yes)
			)
		)
		(pin "2"
		)
		(pin "1"
		)
		(instances
			(project "com-express-7-baseboard"
				(path ""
					(reference "R296")
					(unit 1)
				)
				(path ""
					(reference "R262")
					(unit 1)
				)
			)
		)
	)
	(symbol
		(lib_id "antmicroCapacitors0402:C_100n_0402")
		(at 307.34 170.18 90)
		(unit 1)
		(exclude_from_sim no)
		(in_bom yes)
		(on_board yes)
		(dnp no)
		(fields_autoplaced yes)
		(property "Reference" "C168"
			(at 309.88 166.3636 90)
			(effects
				(font
					(size 1.27 1.27)
					(thickness 0.15)
				)
				(justify right)
			)
		)
		(property "Value" "C_100n_0402"
			(at 317.5 149.86 0)
			(effects
				(font
					(size 1.27 1.27)
					(thickness 0.15)
				)
				(justify left bottom)
				(hide yes)
			)
		)
		(property "Footprint" "antmicro-footprints:C_0402_1005Metric"
			(at 320.04 149.86 0)
			(effects
				(font
					(size 1.27 1.27)
					(thickness 0.15)
				)
				(justify left bottom)
				(hide yes)
			)
		)
		(property "Datasheet" "https://www.murata.com/products/productdetail?partno=GRM155R61H104KE14%23"
			(at 322.58 149.86 0)
			(effects
				(font
					(size 1.27 1.27)
					(thickness 0.15)
				)
				(justify left bottom)
				(hide yes)
			)
		)
		(property "Description" ""
			(at 307.34 170.18 0)
			(effects
				(font
					(size 1.27 1.27)
				)
				(hide yes)
			)
		)
		(property "MPN" "GRM155R61H104KE14D"
			(at 325.12 149.86 0)
			(effects
				(font
					(size 1.27 1.27)
					(thickness 0.15)
				)
				(justify left bottom)
				(hide yes)
			)
		)
		(property "Manufacturer" "Murata"
			(at 327.66 149.86 0)
			(effects
				(font
					(size 1.27 1.27)
					(thickness 0.15)
				)
				(justify left bottom)
				(hide yes)
			)
		)
		(property "License" "Apache-2.0"
			(at 330.2 149.86 0)
			(effects
				(font
					(size 1.27 1.27)
					(thickness 0.15)
				)
				(justify left bottom)
				(hide yes)
			)
		)
		(property "Author" "Antmicro"
			(at 332.74 149.86 0)
			(effects
				(font
					(size 1.27 1.27)
					(thickness 0.15)
				)
				(justify left bottom)
				(hide yes)
			)
		)
		(property "Val" "100n"
			(at 309.88 168.9036 90)
			(effects
				(font
					(size 1.27 1.27)
					(thickness 0.15)
				)
				(justify right)
			)
		)
		(property "Voltage" "50V"
			(at 335.28 149.86 0)
			(effects
				(font
					(size 1.27 1.27)
				)
				(justify left bottom)
				(hide yes)
			)
		)
		(property "Dielectric" "X5R"
			(at 337.82 149.86 0)
			(effects
				(font
					(size 1.27 1.27)
				)
				(justify left bottom)
				(hide yes)
			)
		)
		(property "Public" "False"
			(at 340.36 149.86 0)
			(effects
				(font
					(size 1.27 1.27)
				)
				(justify left bottom)
				(hide yes)
			)
		)
		(pin "2"
		)
		(pin "1"
		)
		(instances
			(project "com-express-7-baseboard"
				(path ""
					(reference "C195")
					(unit 1)
				)
				(path ""
					(reference "C168")
					(unit 1)
				)
			)
		)
	)
	(symbol
		(lib_id "antmicroTestPoints:TP_0.75mm_SMD")
		(at 194.31 198.12 0)
		(unit 1)
		(exclude_from_sim no)
		(in_bom no)
		(on_board yes)
		(dnp no)
		(fields_autoplaced yes)
		(property "Reference" "TP69"
			(at 199.39 198.12 0)
			(effects
				(font
					(size 1.27 1.27)
					(thickness 0.15)
				)
				(justify left)
			)
		)
		(property "Value" "TP_0.75mm_SMD"
			(at 205.105 201.93 0)
			(effects
				(font
					(size 1.27 1.27)
					(thickness 0.15)
				)
				(justify left bottom)
				(hide yes)
			)
		)
		(property "Footprint" "antmicro-footprints:TP_SMD_0.75mm"
			(at 205.105 204.47 0)
			(effects
				(font
					(size 1.27 1.27)
					(thickness 0.15)
				)
				(justify left bottom)
				(hide yes)
			)
		)
		(property "Datasheet" ""
			(at 212.09 210.82 0)
			(effects
				(font
					(size 1.27 1.27)
					(thickness 0.15)
				)
				(justify left bottom)
				(hide yes)
			)
		)
		(property "Description" ""
			(at 194.31 198.12 0)
			(effects
				(font
					(size 1.27 1.27)
				)
				(hide yes)
			)
		)
		(property "MPN" ""
			(at 205.105 209.55 0)
			(effects
				(font
					(size 1.27 1.27)
					(thickness 0.15)
				)
				(justify left bottom)
				(hide yes)
			)
		)
		(property "Manufacturer" ""
			(at 205.105 204.47 0)
			(effects
				(font
					(size 1.27 1.27)
					(thickness 0.15)
				)
				(justify left bottom)
				(hide yes)
			)
		)
		(property "Author" "Antmicro"
			(at 205.105 207.01 0)
			(effects
				(font
					(size 1.27 1.27)
					(thickness 0.15)
				)
				(justify left bottom)
				(hide yes)
			)
		)
		(property "License" "Apache-2.0"
			(at 205.105 209.55 0)
			(effects
				(font
					(size 1.27 1.27)
					(thickness 0.15)
				)
				(justify left bottom)
				(hide yes)
			)
		)
		(property "Public" "False"
			(at 204.47 212.09 0)
			(effects
				(font
					(size 1.27 1.27)
				)
				(justify left bottom)
				(hide yes)
			)
		)
		(pin "1"
		)
		(instances
			(project "com-express-7-baseboard"
				(path ""
					(reference "TP89")
					(unit 1)
				)
				(path ""
					(reference "TP69")
					(unit 1)
				)
			)
		)
	)
	(symbol
		(lib_id "antmicroResistors0402:R_10k_0402")
		(at 193.04 250.19 90)
		(unit 1)
		(exclude_from_sim no)
		(in_bom yes)
		(on_board yes)
		(dnp no)
		(property "Reference" "R261"
			(at 194.31 246.38 90)
			(effects
				(font
					(size 1.27 1.27)
					(thickness 0.15)
				)
				(justify right)
			)
		)
		(property "Value" "R_10k_0402"
			(at 205.74 229.87 0)
			(effects
				(font
					(size 1.27 1.27)
					(thickness 0.15)
				)
				(justify left bottom)
				(hide yes)
			)
		)
		(property "Footprint" "antmicro-footprints:R_0402_1005Metric"
			(at 208.28 229.87 0)
			(effects
				(font
					(size 1.27 1.27)
					(thickness 0.15)
				)
				(justify left bottom)
				(hide yes)
			)
		)
		(property "Datasheet" "https://www.bourns.com/docs/product-datasheets/cr.pdf"
			(at 210.82 229.87 0)
			(effects
				(font
					(size 1.27 1.27)
					(thickness 0.15)
				)
				(justify left bottom)
				(hide yes)
			)
		)
		(property "Description" ""
			(at 193.04 250.19 0)
			(effects
				(font
					(size 1.27 1.27)
				)
				(hide yes)
			)
		)
		(property "MPN" "CR0402-FX-1002GLF"
			(at 213.36 229.87 0)
			(effects
				(font
					(size 1.27 1.27)
					(thickness 0.15)
				)
				(justify left bottom)
				(hide yes)
			)
		)
		(property "Manufacturer" "Bourns"
			(at 215.9 229.87 0)
			(effects
				(font
					(size 1.27 1.27)
					(thickness 0.15)
				)
				(justify left bottom)
				(hide yes)
			)
		)
		(property "License" "Apache-2.0"
			(at 218.44 229.87 0)
			(effects
				(font
					(size 1.27 1.27)
					(thickness 0.15)
				)
				(justify left bottom)
				(hide yes)
			)
		)
		(property "Author" "Antmicro"
			(at 220.98 229.87 0)
			(effects
				(font
					(size 1.27 1.27)
					(thickness 0.15)
				)
				(justify left bottom)
				(hide yes)
			)
		)
		(property "Val" "10k"
			(at 194.31 248.92 90)
			(effects
				(font
					(size 1.27 1.27)
					(thickness 0.15)
				)
				(justify right)
			)
		)
		(property "Tolerance" "1%"
			(at 203.2 229.87 0)
			(effects
				(font
					(size 1.27 1.27)
				)
				(justify left bottom)
				(hide yes)
			)
		)
		(property "Public" "False"
			(at 223.52 229.87 0)
			(effects
				(font
					(size 1.27 1.27)
				)
				(justify left bottom)
				(hide yes)
			)
		)
		(pin "2"
		)
		(pin "1"
		)
		(instances
			(project "com-express-7-baseboard"
				(path ""
					(reference "R295")
					(unit 1)
				)
				(path ""
					(reference "R261")
					(unit 1)
				)
			)
		)
	)
	(symbol
		(lib_id "antmicroCapacitors0402:C_100n_0402")
		(at 129.54 193.04 0)
		(unit 1)
		(exclude_from_sim no)
		(in_bom yes)
		(on_board yes)
		(dnp no)
		(property "Reference" "C152"
			(at 128.27 194.31 0)
			(effects
				(font
					(size 1.27 1.27)
					(thickness 0.15)
				)
			)
		)
		(property "Value" "C_100n_0402"
			(at 149.86 203.2 0)
			(effects
				(font
					(size 1.27 1.27)
					(thickness 0.15)
				)
				(justify left bottom)
				(hide yes)
			)
		)
		(property "Footprint" "antmicro-footprints:C_0402_1005Metric"
			(at 149.86 205.74 0)
			(effects
				(font
					(size 1.27 1.27)
					(thickness 0.15)
				)
				(justify left bottom)
				(hide yes)
			)
		)
		(property "Datasheet" "https://www.murata.com/products/productdetail?partno=GRM155R61H104KE14%23"
			(at 149.86 208.28 0)
			(effects
				(font
					(size 1.27 1.27)
					(thickness 0.15)
				)
				(justify left bottom)
				(hide yes)
			)
		)
		(property "Description" ""
			(at 129.54 193.04 0)
			(effects
				(font
					(size 1.27 1.27)
				)
				(hide yes)
			)
		)
		(property "MPN" "GRM155R61H104KE14D"
			(at 149.86 210.82 0)
			(effects
				(font
					(size 1.27 1.27)
					(thickness 0.15)
				)
				(justify left bottom)
				(hide yes)
			)
		)
		(property "Manufacturer" "Murata"
			(at 149.86 213.36 0)
			(effects
				(font
					(size 1.27 1.27)
					(thickness 0.15)
				)
				(justify left bottom)
				(hide yes)
			)
		)
		(property "License" "Apache-2.0"
			(at 149.86 215.9 0)
			(effects
				(font
					(size 1.27 1.27)
					(thickness 0.15)
				)
				(justify left bottom)
				(hide yes)
			)
		)
		(property "Author" "Antmicro"
			(at 149.86 218.44 0)
			(effects
				(font
					(size 1.27 1.27)
					(thickness 0.15)
				)
				(justify left bottom)
				(hide yes)
			)
		)
		(property "Val" "100n"
			(at 135.89 194.31 0)
			(effects
				(font
					(size 1.27 1.27)
					(thickness 0.15)
				)
			)
		)
		(property "Voltage" "50V"
			(at 149.86 220.98 0)
			(effects
				(font
					(size 1.27 1.27)
				)
				(justify left bottom)
				(hide yes)
			)
		)
		(property "Dielectric" "X5R"
			(at 149.86 223.52 0)
			(effects
				(font
					(size 1.27 1.27)
				)
				(justify left bottom)
				(hide yes)
			)
		)
		(property "Public" "False"
			(at 149.86 226.06 0)
			(effects
				(font
					(size 1.27 1.27)
				)
				(justify left bottom)
				(hide yes)
			)
		)
		(pin "2"
		)
		(pin "1"
		)
		(instances
			(project "com-express-7-baseboard"
				(path ""
					(reference "C179")
					(unit 1)
				)
				(path ""
					(reference "C152")
					(unit 1)
				)
			)
		)
	)
	(symbol
		(lib_id "antmicropower:GND")
		(at 245.11 250.19 0)
		(mirror y)
		(unit 1)
		(exclude_from_sim no)
		(in_bom yes)
		(on_board yes)
		(dnp no)
		(fields_autoplaced yes)
		(property "Reference" "#PWR0350"
			(at 245.11 256.54 0)
			(effects
				(font
					(size 1.27 1.27)
				)
				(justify left bottom)
				(hide yes)
			)
		)
		(property "Value" "GND"
			(at 245.11 255.27 0)
			(effects
				(font
					(size 1.27 1.27)
				)
			)
		)
		(property "Footprint" ""
			(at 245.11 250.19 0)
			(effects
				(font
					(size 1.27 1.27)
				)
				(justify left bottom)
				(hide yes)
			)
		)
		(property "Datasheet" ""
			(at 245.11 250.19 0)
			(effects
				(font
					(size 1.27 1.27)
				)
				(justify left bottom)
				(hide yes)
			)
		)
		(property "Description" ""
			(at 245.11 250.19 0)
			(effects
				(font
					(size 1.27 1.27)
				)
				(hide yes)
			)
		)
		(property "Author" "Antmicro"
			(at 236.22 257.81 0)
			(effects
				(font
					(size 1.27 1.27)
					(thickness 0.15)
				)
				(justify left bottom)
				(hide yes)
			)
		)
		(property "License" "Apache-2.0"
			(at 236.22 260.35 0)
			(effects
				(font
					(size 1.27 1.27)
					(thickness 0.15)
				)
				(justify left bottom)
				(hide yes)
			)
		)
		(pin "1"
		)
		(instances
			(project "com-express-7-baseboard"
				(path ""
					(reference "#PWR0401")
					(unit 1)
				)
				(path ""
					(reference "#PWR0350")
					(unit 1)
				)
			)
		)
	)
	(symbol
		(lib_id "antmicropower:GND")
		(at 297.18 215.9 0)
		(mirror y)
		(unit 1)
		(exclude_from_sim no)
		(in_bom yes)
		(on_board yes)
		(dnp no)
		(fields_autoplaced yes)
		(property "Reference" "#PWR0369"
			(at 297.18 222.25 0)
			(effects
				(font
					(size 1.27 1.27)
				)
				(justify left bottom)
				(hide yes)
			)
		)
		(property "Value" "GND"
			(at 297.18 220.98 0)
			(effects
				(font
					(size 1.27 1.27)
				)
			)
		)
		(property "Footprint" ""
			(at 297.18 215.9 0)
			(effects
				(font
					(size 1.27 1.27)
				)
				(justify left bottom)
				(hide yes)
			)
		)
		(property "Datasheet" ""
			(at 297.18 215.9 0)
			(effects
				(font
					(size 1.27 1.27)
				)
				(justify left bottom)
				(hide yes)
			)
		)
		(property "Description" ""
			(at 297.18 215.9 0)
			(effects
				(font
					(size 1.27 1.27)
				)
				(hide yes)
			)
		)
		(property "Author" "Antmicro"
			(at 288.29 223.52 0)
			(effects
				(font
					(size 1.27 1.27)
					(thickness 0.15)
				)
				(justify left bottom)
				(hide yes)
			)
		)
		(property "License" "Apache-2.0"
			(at 288.29 226.06 0)
			(effects
				(font
					(size 1.27 1.27)
					(thickness 0.15)
				)
				(justify left bottom)
				(hide yes)
			)
		)
		(pin "1"
		)
		(instances
			(project "com-express-7-baseboard"
				(path ""
					(reference "#PWR0420")
					(unit 1)
				)
				(path ""
					(reference "#PWR0369")
					(unit 1)
				)
			)
		)
	)
	(symbol
		(lib_id "antmicroCapacitors0603:C_22u_16V_0603")
		(at 261.62 190.5 90)
		(unit 1)
		(exclude_from_sim no)
		(in_bom yes)
		(on_board yes)
		(dnp no)
		(fields_autoplaced yes)
		(property "Reference" "C155"
			(at 264.16 186.6835 90)
			(effects
				(font
					(size 1.27 1.27)
					(thickness 0.15)
				)
				(justify right)
			)
		)
		(property "Value" "C_22u_16V_0603"
			(at 271.78 170.18 0)
			(effects
				(font
					(size 1.27 1.27)
					(thickness 0.15)
				)
				(justify left bottom)
				(hide yes)
			)
		)
		(property "Footprint" "antmicro-footprints:C_0603_1608Metric"
			(at 274.32 170.18 0)
			(effects
				(font
					(size 1.27 1.27)
					(thickness 0.15)
				)
				(justify left bottom)
				(hide yes)
			)
		)
		(property "Datasheet" "https://product.samsungsem.com/mlcc/CL10A226MO7JZN.do"
			(at 276.86 170.18 0)
			(effects
				(font
					(size 1.27 1.27)
					(thickness 0.15)
				)
				(justify left bottom)
				(hide yes)
			)
		)
		(property "Description" ""
			(at 261.62 190.5 0)
			(effects
				(font
					(size 1.27 1.27)
				)
				(hide yes)
			)
		)
		(property "MPN" "CL10A226MO7JZNC"
			(at 279.4 170.18 0)
			(effects
				(font
					(size 1.27 1.27)
					(thickness 0.15)
				)
				(justify left bottom)
				(hide yes)
			)
		)
		(property "Manufacturer" "Samsung Electro-Mechanics"
			(at 281.94 170.18 0)
			(effects
				(font
					(size 1.27 1.27)
					(thickness 0.15)
				)
				(justify left bottom)
				(hide yes)
			)
		)
		(property "License" "Apache-2.0"
			(at 284.48 170.18 0)
			(effects
				(font
					(size 1.27 1.27)
					(thickness 0.15)
				)
				(justify left bottom)
				(hide yes)
			)
		)
		(property "Author" "Antmicro"
			(at 287.02 170.18 0)
			(effects
				(font
					(size 1.27 1.27)
					(thickness 0.15)
				)
				(justify left bottom)
				(hide yes)
			)
		)
		(property "Val" "22u"
			(at 264.16 189.2235 90)
			(effects
				(font
					(size 1.27 1.27)
					(thickness 0.15)
				)
				(justify right)
			)
		)
		(property "Voltage" "16V"
			(at 289.56 170.18 0)
			(effects
				(font
					(size 1.27 1.27)
				)
				(justify left bottom)
				(hide yes)
			)
		)
		(property "Dielectric" ""
			(at 292.1 170.18 0)
			(effects
				(font
					(size 1.27 1.27)
				)
				(justify left bottom)
				(hide yes)
			)
		)
		(property "Public" "False"
			(at 294.64 170.18 0)
			(effects
				(font
					(size 1.27 1.27)
				)
				(justify left bottom)
				(hide yes)
			)
		)
		(pin "1"
		)
		(pin "2"
		)
		(instances
			(project "com-express-7-baseboard"
				(path ""
					(reference "C182")
					(unit 1)
				)
				(path ""
					(reference "C155")
					(unit 1)
				)
			)
		)
	)
	(symbol
		(lib_id "antmicroCapacitors0402:C_100n_0402")
		(at 125.73 190.5 0)
		(unit 1)
		(exclude_from_sim no)
		(in_bom yes)
		(on_board yes)
		(dnp no)
		(property "Reference" "C151"
			(at 124.46 189.23 0)
			(effects
				(font
					(size 1.27 1.27)
					(thickness 0.15)
				)
			)
		)
		(property "Value" "C_100n_0402"
			(at 146.05 200.66 0)
			(effects
				(font
					(size 1.27 1.27)
					(thickness 0.15)
				)
				(justify left bottom)
				(hide yes)
			)
		)
		(property "Footprint" "antmicro-footprints:C_0402_1005Metric"
			(at 146.05 203.2 0)
			(effects
				(font
					(size 1.27 1.27)
					(thickness 0.15)
				)
				(justify left bottom)
				(hide yes)
			)
		)
		(property "Datasheet" "https://www.murata.com/products/productdetail?partno=GRM155R61H104KE14%23"
			(at 146.05 205.74 0)
			(effects
				(font
					(size 1.27 1.27)
					(thickness 0.15)
				)
				(justify left bottom)
				(hide yes)
			)
		)
		(property "Description" ""
			(at 125.73 190.5 0)
			(effects
				(font
					(size 1.27 1.27)
				)
				(hide yes)
			)
		)
		(property "MPN" "GRM155R61H104KE14D"
			(at 146.05 208.28 0)
			(effects
				(font
					(size 1.27 1.27)
					(thickness 0.15)
				)
				(justify left bottom)
				(hide yes)
			)
		)
		(property "Manufacturer" "Murata"
			(at 146.05 210.82 0)
			(effects
				(font
					(size 1.27 1.27)
					(thickness 0.15)
				)
				(justify left bottom)
				(hide yes)
			)
		)
		(property "License" "Apache-2.0"
			(at 146.05 213.36 0)
			(effects
				(font
					(size 1.27 1.27)
					(thickness 0.15)
				)
				(justify left bottom)
				(hide yes)
			)
		)
		(property "Author" "Antmicro"
			(at 146.05 215.9 0)
			(effects
				(font
					(size 1.27 1.27)
					(thickness 0.15)
				)
				(justify left bottom)
				(hide yes)
			)
		)
		(property "Val" "100n"
			(at 132.08 189.23 0)
			(effects
				(font
					(size 1.27 1.27)
					(thickness 0.15)
				)
			)
		)
		(property "Voltage" "50V"
			(at 146.05 218.44 0)
			(effects
				(font
					(size 1.27 1.27)
				)
				(justify left bottom)
				(hide yes)
			)
		)
		(property "Dielectric" "X5R"
			(at 146.05 220.98 0)
			(effects
				(font
					(size 1.27 1.27)
				)
				(justify left bottom)
				(hide yes)
			)
		)
		(property "Public" "False"
			(at 146.05 223.52 0)
			(effects
				(font
					(size 1.27 1.27)
				)
				(justify left bottom)
				(hide yes)
			)
		)
		(pin "2"
		)
		(pin "1"
		)
		(instances
			(project "com-express-7-baseboard"
				(path ""
					(reference "C178")
					(unit 1)
				)
				(path ""
					(reference "C151")
					(unit 1)
				)
			)
		)
	)
	(symbol
		(lib_id "antmicroCapacitors0402:C_100n_0402")
		(at 327.66 170.18 90)
		(unit 1)
		(exclude_from_sim no)
		(in_bom yes)
		(on_board yes)
		(dnp no)
		(fields_autoplaced yes)
		(property "Reference" "C173"
			(at 330.2 166.3636 90)
			(effects
				(font
					(size 1.27 1.27)
					(thickness 0.15)
				)
				(justify right)
			)
		)
		(property "Value" "C_100n_0402"
			(at 337.82 149.86 0)
			(effects
				(font
					(size 1.27 1.27)
					(thickness 0.15)
				)
				(justify left bottom)
				(hide yes)
			)
		)
		(property "Footprint" "antmicro-footprints:C_0402_1005Metric"
			(at 340.36 149.86 0)
			(effects
				(font
					(size 1.27 1.27)
					(thickness 0.15)
				)
				(justify left bottom)
				(hide yes)
			)
		)
		(property "Datasheet" "https://www.murata.com/products/productdetail?partno=GRM155R61H104KE14%23"
			(at 342.9 149.86 0)
			(effects
				(font
					(size 1.27 1.27)
					(thickness 0.15)
				)
				(justify left bottom)
				(hide yes)
			)
		)
		(property "Description" ""
			(at 327.66 170.18 0)
			(effects
				(font
					(size 1.27 1.27)
				)
				(hide yes)
			)
		)
		(property "MPN" "GRM155R61H104KE14D"
			(at 345.44 149.86 0)
			(effects
				(font
					(size 1.27 1.27)
					(thickness 0.15)
				)
				(justify left bottom)
				(hide yes)
			)
		)
		(property "Manufacturer" "Murata"
			(at 347.98 149.86 0)
			(effects
				(font
					(size 1.27 1.27)
					(thickness 0.15)
				)
				(justify left bottom)
				(hide yes)
			)
		)
		(property "License" "Apache-2.0"
			(at 350.52 149.86 0)
			(effects
				(font
					(size 1.27 1.27)
					(thickness 0.15)
				)
				(justify left bottom)
				(hide yes)
			)
		)
		(property "Author" "Antmicro"
			(at 353.06 149.86 0)
			(effects
				(font
					(size 1.27 1.27)
					(thickness 0.15)
				)
				(justify left bottom)
				(hide yes)
			)
		)
		(property "Val" "100n"
			(at 330.2 168.9036 90)
			(effects
				(font
					(size 1.27 1.27)
					(thickness 0.15)
				)
				(justify right)
			)
		)
		(property "Voltage" "50V"
			(at 355.6 149.86 0)
			(effects
				(font
					(size 1.27 1.27)
				)
				(justify left bottom)
				(hide yes)
			)
		)
		(property "Dielectric" "X5R"
			(at 358.14 149.86 0)
			(effects
				(font
					(size 1.27 1.27)
				)
				(justify left bottom)
				(hide yes)
			)
		)
		(property "Public" "False"
			(at 360.68 149.86 0)
			(effects
				(font
					(size 1.27 1.27)
				)
				(justify left bottom)
				(hide yes)
			)
		)
		(pin "2"
		)
		(pin "1"
		)
		(instances
			(project "com-express-7-baseboard"
				(path ""
					(reference "C200")
					(unit 1)
				)
				(path ""
					(reference "C173")
					(unit 1)
				)
			)
		)
	)
	(symbol
		(lib_id "antmicroTestPoints:TP_0.75mm_SMD")
		(at 149.86 223.52 0)
		(mirror y)
		(unit 1)
		(exclude_from_sim no)
		(in_bom no)
		(on_board yes)
		(dnp no)
		(property "Reference" "TP64"
			(at 144.78 223.52 0)
			(effects
				(font
					(size 1.27 1.27)
					(thickness 0.15)
				)
				(justify left)
			)
		)
		(property "Value" "TP_0.75mm_SMD"
			(at 139.065 227.33 0)
			(effects
				(font
					(size 1.27 1.27)
					(thickness 0.15)
				)
				(justify left bottom)
				(hide yes)
			)
		)
		(property "Footprint" "antmicro-footprints:TP_SMD_0.75mm"
			(at 139.065 229.87 0)
			(effects
				(font
					(size 1.27 1.27)
					(thickness 0.15)
				)
				(justify left bottom)
				(hide yes)
			)
		)
		(property "Datasheet" ""
			(at 132.08 236.22 0)
			(effects
				(font
					(size 1.27 1.27)
					(thickness 0.15)
				)
				(justify left bottom)
				(hide yes)
			)
		)
		(property "Description" ""
			(at 149.86 223.52 0)
			(effects
				(font
					(size 1.27 1.27)
				)
				(hide yes)
			)
		)
		(property "MPN" ""
			(at 139.065 234.95 0)
			(effects
				(font
					(size 1.27 1.27)
					(thickness 0.15)
				)
				(justify left bottom)
				(hide yes)
			)
		)
		(property "Manufacturer" ""
			(at 139.065 229.87 0)
			(effects
				(font
					(size 1.27 1.27)
					(thickness 0.15)
				)
				(justify left bottom)
				(hide yes)
			)
		)
		(property "Author" "Antmicro"
			(at 139.065 232.41 0)
			(effects
				(font
					(size 1.27 1.27)
					(thickness 0.15)
				)
				(justify left bottom)
				(hide yes)
			)
		)
		(property "License" "Apache-2.0"
			(at 139.065 234.95 0)
			(effects
				(font
					(size 1.27 1.27)
					(thickness 0.15)
				)
				(justify left bottom)
				(hide yes)
			)
		)
		(property "Public" "False"
			(at 139.7 237.49 0)
			(effects
				(font
					(size 1.27 1.27)
				)
				(justify left bottom)
				(hide yes)
			)
		)
		(pin "1"
		)
		(instances
			(project "com-express-7-baseboard"
				(path ""
					(reference "TP84")
					(unit 1)
				)
				(path ""
					(reference "TP64")
					(unit 1)
				)
			)
		)
	)
	(symbol
		(lib_id "antmicropower:GND")
		(at 276.86 238.76 0)
		(mirror y)
		(unit 1)
		(exclude_from_sim no)
		(in_bom yes)
		(on_board yes)
		(dnp no)
		(fields_autoplaced yes)
		(property "Reference" "#PWR0362"
			(at 276.86 245.11 0)
			(effects
				(font
					(size 1.27 1.27)
				)
				(justify left bottom)
				(hide yes)
			)
		)
		(property "Value" "GND"
			(at 276.86 243.84 0)
			(effects
				(font
					(size 1.27 1.27)
				)
			)
		)
		(property "Footprint" ""
			(at 276.86 238.76 0)
			(effects
				(font
					(size 1.27 1.27)
				)
				(justify left bottom)
				(hide yes)
			)
		)
		(property "Datasheet" ""
			(at 276.86 238.76 0)
			(effects
				(font
					(size 1.27 1.27)
				)
				(justify left bottom)
				(hide yes)
			)
		)
		(property "Description" ""
			(at 276.86 238.76 0)
			(effects
				(font
					(size 1.27 1.27)
				)
				(hide yes)
			)
		)
		(property "Author" "Antmicro"
			(at 267.97 246.38 0)
			(effects
				(font
					(size 1.27 1.27)
					(thickness 0.15)
				)
				(justify left bottom)
				(hide yes)
			)
		)
		(property "License" "Apache-2.0"
			(at 267.97 248.92 0)
			(effects
				(font
					(size 1.27 1.27)
					(thickness 0.15)
				)
				(justify left bottom)
				(hide yes)
			)
		)
		(pin "1"
		)
		(instances
			(project "com-express-7-baseboard"
				(path ""
					(reference "#PWR0413")
					(unit 1)
				)
				(path ""
					(reference "#PWR0362")
					(unit 1)
				)
			)
		)
	)
	(symbol
		(lib_id "antmicroCapacitors0402:C_100n_0402")
		(at 276.86 238.76 90)
		(unit 1)
		(exclude_from_sim no)
		(in_bom yes)
		(on_board yes)
		(dnp no)
		(fields_autoplaced yes)
		(property "Reference" "C160"
			(at 279.4 234.9436 90)
			(effects
				(font
					(size 1.27 1.27)
					(thickness 0.15)
				)
				(justify right)
			)
		)
		(property "Value" "C_100n_0402"
			(at 287.02 218.44 0)
			(effects
				(font
					(size 1.27 1.27)
					(thickness 0.15)
				)
				(justify left bottom)
				(hide yes)
			)
		)
		(property "Footprint" "antmicro-footprints:C_0402_1005Metric"
			(at 289.56 218.44 0)
			(effects
				(font
					(size 1.27 1.27)
					(thickness 0.15)
				)
				(justify left bottom)
				(hide yes)
			)
		)
		(property "Datasheet" "https://www.murata.com/products/productdetail?partno=GRM155R61H104KE14%23"
			(at 292.1 218.44 0)
			(effects
				(font
					(size 1.27 1.27)
					(thickness 0.15)
				)
				(justify left bottom)
				(hide yes)
			)
		)
		(property "Description" ""
			(at 276.86 238.76 0)
			(effects
				(font
					(size 1.27 1.27)
				)
				(hide yes)
			)
		)
		(property "MPN" "GRM155R61H104KE14D"
			(at 294.64 218.44 0)
			(effects
				(font
					(size 1.27 1.27)
					(thickness 0.15)
				)
				(justify left bottom)
				(hide yes)
			)
		)
		(property "Manufacturer" "Murata"
			(at 297.18 218.44 0)
			(effects
				(font
					(size 1.27 1.27)
					(thickness 0.15)
				)
				(justify left bottom)
				(hide yes)
			)
		)
		(property "License" "Apache-2.0"
			(at 299.72 218.44 0)
			(effects
				(font
					(size 1.27 1.27)
					(thickness 0.15)
				)
				(justify left bottom)
				(hide yes)
			)
		)
		(property "Author" "Antmicro"
			(at 302.26 218.44 0)
			(effects
				(font
					(size 1.27 1.27)
					(thickness 0.15)
				)
				(justify left bottom)
				(hide yes)
			)
		)
		(property "Val" "100n"
			(at 279.4 237.4836 90)
			(effects
				(font
					(size 1.27 1.27)
					(thickness 0.15)
				)
				(justify right)
			)
		)
		(property "Voltage" "50V"
			(at 304.8 218.44 0)
			(effects
				(font
					(size 1.27 1.27)
				)
				(justify left bottom)
				(hide yes)
			)
		)
		(property "Dielectric" "X5R"
			(at 307.34 218.44 0)
			(effects
				(font
					(size 1.27 1.27)
				)
				(justify left bottom)
				(hide yes)
			)
		)
		(property "Public" "False"
			(at 309.88 218.44 0)
			(effects
				(font
					(size 1.27 1.27)
				)
				(justify left bottom)
				(hide yes)
			)
		)
		(pin "2"
		)
		(pin "1"
		)
		(instances
			(project "com-express-7-baseboard"
				(path ""
					(reference "C187")
					(unit 1)
				)
				(path ""
					(reference "C160")
					(unit 1)
				)
			)
		)
	)
	(symbol
		(lib_id "antmicropower:+1V8")
		(at 144.78 176.53 0)
		(unit 1)
		(exclude_from_sim no)
		(in_bom yes)
		(on_board yes)
		(dnp no)
		(property "Reference" "#PWR0339"
			(at 160.02 179.07 0)
			(effects
				(font
					(size 1.27 1.27)
					(thickness 0.15)
				)
				(justify left bottom)
				(hide yes)
			)
		)
		(property "Value" "+1V8"
			(at 144.78 172.72 0)
			(effects
				(font
					(size 1.27 1.27)
					(thickness 0.15)
				)
			)
		)
		(property "Footprint" ""
			(at 160.02 184.15 0)
			(effects
				(font
					(size 1.27 1.27)
					(thickness 0.15)
				)
				(justify left bottom)
				(hide yes)
			)
		)
		(property "Datasheet" ""
			(at 160.02 186.69 0)
			(effects
				(font
					(size 1.27 1.27)
					(thickness 0.15)
				)
				(justify left bottom)
				(hide yes)
			)
		)
		(property "Description" ""
			(at 144.78 176.53 0)
			(effects
				(font
					(size 1.27 1.27)
				)
				(hide yes)
			)
		)
		(property "Author" "Antmicro"
			(at 160.02 181.61 0)
			(effects
				(font
					(size 1.27 1.27)
					(thickness 0.15)
				)
				(justify left bottom)
				(hide yes)
			)
		)
		(property "License" "Apache-2.0"
			(at 160.02 184.15 0)
			(effects
				(font
					(size 1.27 1.27)
					(thickness 0.15)
				)
				(justify left bottom)
				(hide yes)
			)
		)
		(pin "1"
		)
		(instances
			(project "com-express-7-baseboard"
				(path ""
					(reference "#PWR0390")
					(unit 1)
				)
				(path ""
					(reference "#PWR0339")
					(unit 1)
				)
			)
		)
	)
	(symbol
		(lib_id "antmicroResistorsmisc:R_0R_0201")
		(at 128.27 78.74 0)
		(unit 1)
		(exclude_from_sim no)
		(in_bom yes)
		(on_board yes)
		(dnp no)
		(property "Reference" "R257"
			(at 125.73 80.01 0)
			(effects
				(font
					(size 1.27 1.27)
					(thickness 0.15)
				)
			)
		)
		(property "Value" "R_0R_0201"
			(at 148.59 91.44 0)
			(effects
				(font
					(size 1.27 1.27)
					(thickness 0.15)
				)
				(justify left bottom)
				(hide yes)
			)
		)
		(property "Footprint" "antmicro-footprints:R_0201"
			(at 148.59 93.98 0)
			(effects
				(font
					(size 1.27 1.27)
					(thickness 0.15)
				)
				(justify left bottom)
				(hide yes)
			)
		)
		(property "Datasheet" "https://www.bourns.com/docs/product-datasheets/cr.pdf"
			(at 148.59 96.52 0)
			(effects
				(font
					(size 1.27 1.27)
					(thickness 0.15)
				)
				(justify left bottom)
				(hide yes)
			)
		)
		(property "Description" ""
			(at 128.27 78.74 0)
			(effects
				(font
					(size 1.27 1.27)
				)
				(hide yes)
			)
		)
		(property "MPN" "CR0201-FX-0R00GLF"
			(at 148.59 99.06 0)
			(effects
				(font
					(size 1.27 1.27)
					(thickness 0.15)
				)
				(justify left bottom)
				(hide yes)
			)
		)
		(property "Manufacturer" "Bourns"
			(at 148.59 101.6 0)
			(effects
				(font
					(size 1.27 1.27)
					(thickness 0.15)
				)
				(justify left bottom)
				(hide yes)
			)
		)
		(property "License" "Apache-2.0"
			(at 148.59 104.14 0)
			(effects
				(font
					(size 1.27 1.27)
					(thickness 0.15)
				)
				(justify left bottom)
				(hide yes)
			)
		)
		(property "Author" "Antmicro"
			(at 148.59 106.68 0)
			(effects
				(font
					(size 1.27 1.27)
					(thickness 0.15)
				)
				(justify left bottom)
				(hide yes)
			)
		)
		(property "Val" "0R"
			(at 134.62 80.01 0)
			(effects
				(font
					(size 1.27 1.27)
					(thickness 0.15)
				)
			)
		)
		(property "Tolerance" "1%"
			(at 148.59 88.9 0)
			(effects
				(font
					(size 1.27 1.27)
				)
				(justify left bottom)
				(hide yes)
			)
		)
		(pin "1"
		)
		(pin "2"
		)
		(instances
			(project "com-express-7-baseboard"
				(path ""
					(reference "R291")
					(unit 1)
				)
				(path ""
					(reference "R257")
					(unit 1)
				)
			)
		)
	)
	(symbol
		(lib_id "antmicroCapacitors0402:C_100n_0402")
		(at 307.34 193.04 90)
		(unit 1)
		(exclude_from_sim no)
		(in_bom yes)
		(on_board yes)
		(dnp no)
		(fields_autoplaced yes)
		(property "Reference" "C169"
			(at 309.88 189.2236 90)
			(effects
				(font
					(size 1.27 1.27)
					(thickness 0.15)
				)
				(justify right)
			)
		)
		(property "Value" "C_100n_0402"
			(at 317.5 172.72 0)
			(effects
				(font
					(size 1.27 1.27)
					(thickness 0.15)
				)
				(justify left bottom)
				(hide yes)
			)
		)
		(property "Footprint" "antmicro-footprints:C_0402_1005Metric"
			(at 320.04 172.72 0)
			(effects
				(font
					(size 1.27 1.27)
					(thickness 0.15)
				)
				(justify left bottom)
				(hide yes)
			)
		)
		(property "Datasheet" "https://www.murata.com/products/productdetail?partno=GRM155R61H104KE14%23"
			(at 322.58 172.72 0)
			(effects
				(font
					(size 1.27 1.27)
					(thickness 0.15)
				)
				(justify left bottom)
				(hide yes)
			)
		)
		(property "Description" ""
			(at 307.34 193.04 0)
			(effects
				(font
					(size 1.27 1.27)
				)
				(hide yes)
			)
		)
		(property "MPN" "GRM155R61H104KE14D"
			(at 325.12 172.72 0)
			(effects
				(font
					(size 1.27 1.27)
					(thickness 0.15)
				)
				(justify left bottom)
				(hide yes)
			)
		)
		(property "Manufacturer" "Murata"
			(at 327.66 172.72 0)
			(effects
				(font
					(size 1.27 1.27)
					(thickness 0.15)
				)
				(justify left bottom)
				(hide yes)
			)
		)
		(property "License" "Apache-2.0"
			(at 330.2 172.72 0)
			(effects
				(font
					(size 1.27 1.27)
					(thickness 0.15)
				)
				(justify left bottom)
				(hide yes)
			)
		)
		(property "Author" "Antmicro"
			(at 332.74 172.72 0)
			(effects
				(font
					(size 1.27 1.27)
					(thickness 0.15)
				)
				(justify left bottom)
				(hide yes)
			)
		)
		(property "Val" "100n"
			(at 309.88 191.7636 90)
			(effects
				(font
					(size 1.27 1.27)
					(thickness 0.15)
				)
				(justify right)
			)
		)
		(property "Voltage" "50V"
			(at 335.28 172.72 0)
			(effects
				(font
					(size 1.27 1.27)
				)
				(justify left bottom)
				(hide yes)
			)
		)
		(property "Dielectric" "X5R"
			(at 337.82 172.72 0)
			(effects
				(font
					(size 1.27 1.27)
				)
				(justify left bottom)
				(hide yes)
			)
		)
		(property "Public" "False"
			(at 340.36 172.72 0)
			(effects
				(font
					(size 1.27 1.27)
				)
				(justify left bottom)
				(hide yes)
			)
		)
		(pin "2"
		)
		(pin "1"
		)
		(instances
			(project "com-express-7-baseboard"
				(path ""
					(reference "C196")
					(unit 1)
				)
				(path ""
					(reference "C169")
					(unit 1)
				)
			)
		)
	)
	(symbol
		(lib_id "antmicroResistors0402:R_10k_0402")
		(at 125.73 220.98 90)
		(unit 1)
		(exclude_from_sim no)
		(in_bom yes)
		(on_board yes)
		(dnp no)
		(fields_autoplaced yes)
		(property "Reference" "R253"
			(at 128.27 217.17 90)
			(effects
				(font
					(size 1.27 1.27)
					(thickness 0.15)
				)
				(justify right)
			)
		)
		(property "Value" "R_10k_0402"
			(at 138.43 200.66 0)
			(effects
				(font
					(size 1.27 1.27)
					(thickness 0.15)
				)
				(justify left bottom)
				(hide yes)
			)
		)
		(property "Footprint" "antmicro-footprints:R_0402_1005Metric"
			(at 140.97 200.66 0)
			(effects
				(font
					(size 1.27 1.27)
					(thickness 0.15)
				)
				(justify left bottom)
				(hide yes)
			)
		)
		(property "Datasheet" "https://www.bourns.com/docs/product-datasheets/cr.pdf"
			(at 143.51 200.66 0)
			(effects
				(font
					(size 1.27 1.27)
					(thickness 0.15)
				)
				(justify left bottom)
				(hide yes)
			)
		)
		(property "Description" ""
			(at 125.73 220.98 0)
			(effects
				(font
					(size 1.27 1.27)
				)
				(hide yes)
			)
		)
		(property "MPN" "CR0402-FX-1002GLF"
			(at 146.05 200.66 0)
			(effects
				(font
					(size 1.27 1.27)
					(thickness 0.15)
				)
				(justify left bottom)
				(hide yes)
			)
		)
		(property "Manufacturer" "Bourns"
			(at 148.59 200.66 0)
			(effects
				(font
					(size 1.27 1.27)
					(thickness 0.15)
				)
				(justify left bottom)
				(hide yes)
			)
		)
		(property "License" "Apache-2.0"
			(at 151.13 200.66 0)
			(effects
				(font
					(size 1.27 1.27)
					(thickness 0.15)
				)
				(justify left bottom)
				(hide yes)
			)
		)
		(property "Author" "Antmicro"
			(at 153.67 200.66 0)
			(effects
				(font
					(size 1.27 1.27)
					(thickness 0.15)
				)
				(justify left bottom)
				(hide yes)
			)
		)
		(property "Val" "10k"
			(at 128.27 219.71 90)
			(effects
				(font
					(size 1.27 1.27)
					(thickness 0.15)
				)
				(justify right)
			)
		)
		(property "Tolerance" "1%"
			(at 135.89 200.66 0)
			(effects
				(font
					(size 1.27 1.27)
				)
				(justify left bottom)
				(hide yes)
			)
		)
		(property "Public" "False"
			(at 156.21 200.66 0)
			(effects
				(font
					(size 1.27 1.27)
				)
				(justify left bottom)
				(hide yes)
			)
		)
		(pin "2"
		)
		(pin "1"
		)
		(instances
			(project "com-express-7-baseboard"
				(path ""
					(reference "R287")
					(unit 1)
				)
				(path ""
					(reference "R253")
					(unit 1)
				)
			)
		)
	)
	(symbol
		(lib_id "antmicropower:+1V0")
		(at 276.86 161.29 0)
		(unit 1)
		(exclude_from_sim no)
		(in_bom yes)
		(on_board yes)
		(dnp no)
		(property "Reference" "#PWR0355"
			(at 276.86 165.1 0)
			(effects
				(font
					(size 1.27 1.27)
				)
				(hide yes)
			)
		)
		(property "Value" "+1V0"
			(at 276.86 157.48 0)
			(effects
				(font
					(size 1.27 1.27)
				)
			)
		)
		(property "Footprint" ""
			(at 276.86 161.29 0)
			(effects
				(font
					(size 1.27 1.27)
				)
				(hide yes)
			)
		)
		(property "Datasheet" ""
			(at 276.86 161.29 0)
			(effects
				(font
					(size 1.27 1.27)
				)
				(hide yes)
			)
		)
		(property "Description" ""
			(at 276.86 161.29 0)
			(effects
				(font
					(size 1.27 1.27)
				)
				(hide yes)
			)
		)
		(pin "1"
		)
		(instances
			(project "com-express-7-baseboard"
				(path ""
					(reference "#PWR0406")
					(unit 1)
				)
				(path ""
					(reference "#PWR0355")
					(unit 1)
				)
			)
		)
	)
	(symbol
		(lib_id "antmicropower:+1V8")
		(at 105.41 212.09 0)
		(unit 1)
		(exclude_from_sim no)
		(in_bom yes)
		(on_board yes)
		(dnp no)
		(property "Reference" "#PWR0333"
			(at 120.65 214.63 0)
			(effects
				(font
					(size 1.27 1.27)
					(thickness 0.15)
				)
				(justify left bottom)
				(hide yes)
			)
		)
		(property "Value" "+1V8"
			(at 105.41 208.28 0)
			(effects
				(font
					(size 1.27 1.27)
					(thickness 0.15)
				)
			)
		)
		(property "Footprint" ""
			(at 120.65 219.71 0)
			(effects
				(font
					(size 1.27 1.27)
					(thickness 0.15)
				)
				(justify left bottom)
				(hide yes)
			)
		)
		(property "Datasheet" ""
			(at 120.65 222.25 0)
			(effects
				(font
					(size 1.27 1.27)
					(thickness 0.15)
				)
				(justify left bottom)
				(hide yes)
			)
		)
		(property "Description" ""
			(at 105.41 212.09 0)
			(effects
				(font
					(size 1.27 1.27)
				)
				(hide yes)
			)
		)
		(property "Author" "Antmicro"
			(at 120.65 217.17 0)
			(effects
				(font
					(size 1.27 1.27)
					(thickness 0.15)
				)
				(justify left bottom)
				(hide yes)
			)
		)
		(property "License" "Apache-2.0"
			(at 120.65 219.71 0)
			(effects
				(font
					(size 1.27 1.27)
					(thickness 0.15)
				)
				(justify left bottom)
				(hide yes)
			)
		)
		(pin "1"
		)
		(instances
			(project "com-express-7-baseboard"
				(path ""
					(reference "#PWR0384")
					(unit 1)
				)
				(path ""
					(reference "#PWR0333")
					(unit 1)
				)
			)
		)
	)
	(symbol
		(lib_id "antmicroTestPoints:TP_0.75mm_SMD")
		(at 186.69 121.92 0)
		(unit 1)
		(exclude_from_sim no)
		(in_bom no)
		(on_board yes)
		(dnp no)
		(fields_autoplaced yes)
		(property "Reference" "TP73"
			(at 191.77 121.92 0)
			(effects
				(font
					(size 1.27 1.27)
					(thickness 0.15)
				)
				(justify left)
			)
		)
		(property "Value" "TP_0.75mm_SMD"
			(at 197.485 125.73 0)
			(effects
				(font
					(size 1.27 1.27)
					(thickness 0.15)
				)
				(justify left bottom)
				(hide yes)
			)
		)
		(property "Footprint" "antmicro-footprints:TP_SMD_0.75mm"
			(at 197.485 128.27 0)
			(effects
				(font
					(size 1.27 1.27)
					(thickness 0.15)
				)
				(justify left bottom)
				(hide yes)
			)
		)
		(property "Datasheet" ""
			(at 204.47 134.62 0)
			(effects
				(font
					(size 1.27 1.27)
					(thickness 0.15)
				)
				(justify left bottom)
				(hide yes)
			)
		)
		(property "Description" ""
			(at 186.69 121.92 0)
			(effects
				(font
					(size 1.27 1.27)
				)
				(hide yes)
			)
		)
		(property "MPN" ""
			(at 197.485 133.35 0)
			(effects
				(font
					(size 1.27 1.27)
					(thickness 0.15)
				)
				(justify left bottom)
				(hide yes)
			)
		)
		(property "Manufacturer" ""
			(at 197.485 128.27 0)
			(effects
				(font
					(size 1.27 1.27)
					(thickness 0.15)
				)
				(justify left bottom)
				(hide yes)
			)
		)
		(property "Author" "Antmicro"
			(at 197.485 130.81 0)
			(effects
				(font
					(size 1.27 1.27)
					(thickness 0.15)
				)
				(justify left bottom)
				(hide yes)
			)
		)
		(property "License" "Apache-2.0"
			(at 197.485 133.35 0)
			(effects
				(font
					(size 1.27 1.27)
					(thickness 0.15)
				)
				(justify left bottom)
				(hide yes)
			)
		)
		(property "Public" "False"
			(at 196.85 135.89 0)
			(effects
				(font
					(size 1.27 1.27)
				)
				(justify left bottom)
				(hide yes)
			)
		)
		(pin "1"
		)
		(instances
			(project "com-express-7-baseboard"
				(path ""
					(reference "TP93")
					(unit 1)
				)
				(path ""
					(reference "TP73")
					(unit 1)
				)
			)
		)
	)
	(symbol
		(lib_id "antmicroCapacitors0402:C_100n_0402")
		(at 297.18 170.18 90)
		(unit 1)
		(exclude_from_sim no)
		(in_bom yes)
		(on_board yes)
		(dnp no)
		(fields_autoplaced yes)
		(property "Reference" "C165"
			(at 299.72 166.3636 90)
			(effects
				(font
					(size 1.27 1.27)
					(thickness 0.15)
				)
				(justify right)
			)
		)
		(property "Value" "C_100n_0402"
			(at 307.34 149.86 0)
			(effects
				(font
					(size 1.27 1.27)
					(thickness 0.15)
				)
				(justify left bottom)
				(hide yes)
			)
		)
		(property "Footprint" "antmicro-footprints:C_0402_1005Metric"
			(at 309.88 149.86 0)
			(effects
				(font
					(size 1.27 1.27)
					(thickness 0.15)
				)
				(justify left bottom)
				(hide yes)
			)
		)
		(property "Datasheet" "https://www.murata.com/products/productdetail?partno=GRM155R61H104KE14%23"
			(at 312.42 149.86 0)
			(effects
				(font
					(size 1.27 1.27)
					(thickness 0.15)
				)
				(justify left bottom)
				(hide yes)
			)
		)
		(property "Description" ""
			(at 297.18 170.18 0)
			(effects
				(font
					(size 1.27 1.27)
				)
				(hide yes)
			)
		)
		(property "MPN" "GRM155R61H104KE14D"
			(at 314.96 149.86 0)
			(effects
				(font
					(size 1.27 1.27)
					(thickness 0.15)
				)
				(justify left bottom)
				(hide yes)
			)
		)
		(property "Manufacturer" "Murata"
			(at 317.5 149.86 0)
			(effects
				(font
					(size 1.27 1.27)
					(thickness 0.15)
				)
				(justify left bottom)
				(hide yes)
			)
		)
		(property "License" "Apache-2.0"
			(at 320.04 149.86 0)
			(effects
				(font
					(size 1.27 1.27)
					(thickness 0.15)
				)
				(justify left bottom)
				(hide yes)
			)
		)
		(property "Author" "Antmicro"
			(at 322.58 149.86 0)
			(effects
				(font
					(size 1.27 1.27)
					(thickness 0.15)
				)
				(justify left bottom)
				(hide yes)
			)
		)
		(property "Val" "100n"
			(at 299.72 168.9036 90)
			(effects
				(font
					(size 1.27 1.27)
					(thickness 0.15)
				)
				(justify right)
			)
		)
		(property "Voltage" "50V"
			(at 325.12 149.86 0)
			(effects
				(font
					(size 1.27 1.27)
				)
				(justify left bottom)
				(hide yes)
			)
		)
		(property "Dielectric" "X5R"
			(at 327.66 149.86 0)
			(effects
				(font
					(size 1.27 1.27)
				)
				(justify left bottom)
				(hide yes)
			)
		)
		(property "Public" "False"
			(at 330.2 149.86 0)
			(effects
				(font
					(size 1.27 1.27)
				)
				(justify left bottom)
				(hide yes)
			)
		)
		(pin "2"
		)
		(pin "1"
		)
		(instances
			(project "com-express-7-baseboard"
				(path ""
					(reference "C192")
					(unit 1)
				)
				(path ""
					(reference "C165")
					(unit 1)
				)
			)
		)
	)
	(symbol
		(lib_id "antmicroResistors0402:R_10k_0402")
		(at 199.39 121.92 90)
		(unit 1)
		(exclude_from_sim no)
		(in_bom yes)
		(on_board yes)
		(dnp no)
		(fields_autoplaced yes)
		(property "Reference" "R264"
			(at 201.93 118.11 90)
			(effects
				(font
					(size 1.27 1.27)
					(thickness 0.15)
				)
				(justify right)
			)
		)
		(property "Value" "R_10k_0402"
			(at 212.09 101.6 0)
			(effects
				(font
					(size 1.27 1.27)
					(thickness 0.15)
				)
				(justify left bottom)
				(hide yes)
			)
		)
		(property "Footprint" "antmicro-footprints:R_0402_1005Metric"
			(at 214.63 101.6 0)
			(effects
				(font
					(size 1.27 1.27)
					(thickness 0.15)
				)
				(justify left bottom)
				(hide yes)
			)
		)
		(property "Datasheet" "https://www.bourns.com/docs/product-datasheets/cr.pdf"
			(at 217.17 101.6 0)
			(effects
				(font
					(size 1.27 1.27)
					(thickness 0.15)
				)
				(justify left bottom)
				(hide yes)
			)
		)
		(property "Description" ""
			(at 199.39 121.92 0)
			(effects
				(font
					(size 1.27 1.27)
				)
				(hide yes)
			)
		)
		(property "MPN" "CR0402-FX-1002GLF"
			(at 219.71 101.6 0)
			(effects
				(font
					(size 1.27 1.27)
					(thickness 0.15)
				)
				(justify left bottom)
				(hide yes)
			)
		)
		(property "Manufacturer" "Bourns"
			(at 222.25 101.6 0)
			(effects
				(font
					(size 1.27 1.27)
					(thickness 0.15)
				)
				(justify left bottom)
				(hide yes)
			)
		)
		(property "License" "Apache-2.0"
			(at 224.79 101.6 0)
			(effects
				(font
					(size 1.27 1.27)
					(thickness 0.15)
				)
				(justify left bottom)
				(hide yes)
			)
		)
		(property "Author" "Antmicro"
			(at 227.33 101.6 0)
			(effects
				(font
					(size 1.27 1.27)
					(thickness 0.15)
				)
				(justify left bottom)
				(hide yes)
			)
		)
		(property "Val" "10k"
			(at 201.93 120.65 90)
			(effects
				(font
					(size 1.27 1.27)
					(thickness 0.15)
				)
				(justify right)
			)
		)
		(property "Tolerance" "1%"
			(at 209.55 101.6 0)
			(effects
				(font
					(size 1.27 1.27)
				)
				(justify left bottom)
				(hide yes)
			)
		)
		(property "Public" "False"
			(at 229.87 101.6 0)
			(effects
				(font
					(size 1.27 1.27)
				)
				(justify left bottom)
				(hide yes)
			)
		)
		(pin "2"
		)
		(pin "1"
		)
		(instances
			(project "com-express-7-baseboard"
				(path ""
					(reference "R298")
					(unit 1)
				)
				(path ""
					(reference "R264")
					(unit 1)
				)
			)
		)
	)
	(symbol
		(lib_id "antmicroResistors0402:R_10k_0402")
		(at 193.04 223.52 90)
		(unit 1)
		(exclude_from_sim no)
		(in_bom yes)
		(on_board yes)
		(dnp yes)
		(property "Reference" "R260"
			(at 194.31 218.44 90)
			(effects
				(font
					(size 1.27 1.27)
					(thickness 0.15)
				)
				(justify right)
			)
		)
		(property "Value" "R_10k_0402"
			(at 205.74 203.2 0)
			(effects
				(font
					(size 1.27 1.27)
					(thickness 0.15)
				)
				(justify left bottom)
				(hide yes)
			)
		)
		(property "Footprint" "antmicro-footprints:R_0402_1005Metric"
			(at 208.28 203.2 0)
			(effects
				(font
					(size 1.27 1.27)
					(thickness 0.15)
				)
				(justify left bottom)
				(hide yes)
			)
		)
		(property "Datasheet" "https://www.bourns.com/docs/product-datasheets/cr.pdf"
			(at 210.82 203.2 0)
			(effects
				(font
					(size 1.27 1.27)
					(thickness 0.15)
				)
				(justify left bottom)
				(hide yes)
			)
		)
		(property "Description" ""
			(at 193.04 223.52 0)
			(effects
				(font
					(size 1.27 1.27)
				)
				(hide yes)
			)
		)
		(property "MPN" "CR0402-FX-1002GLF"
			(at 213.36 203.2 0)
			(effects
				(font
					(size 1.27 1.27)
					(thickness 0.15)
				)
				(justify left bottom)
				(hide yes)
			)
		)
		(property "Manufacturer" "Bourns"
			(at 215.9 203.2 0)
			(effects
				(font
					(size 1.27 1.27)
					(thickness 0.15)
				)
				(justify left bottom)
				(hide yes)
			)
		)
		(property "License" "Apache-2.0"
			(at 218.44 203.2 0)
			(effects
				(font
					(size 1.27 1.27)
					(thickness 0.15)
				)
				(justify left bottom)
				(hide yes)
			)
		)
		(property "Author" "Antmicro"
			(at 220.98 203.2 0)
			(effects
				(font
					(size 1.27 1.27)
					(thickness 0.15)
				)
				(justify left bottom)
				(hide yes)
			)
		)
		(property "Val" "10k"
			(at 194.31 220.98 90)
			(effects
				(font
					(size 1.27 1.27)
					(thickness 0.15)
				)
				(justify right)
			)
		)
		(property "Tolerance" "1%"
			(at 203.2 203.2 0)
			(effects
				(font
					(size 1.27 1.27)
				)
				(justify left bottom)
				(hide yes)
			)
		)
		(property "Public" "False"
			(at 223.52 203.2 0)
			(effects
				(font
					(size 1.27 1.27)
				)
				(justify left bottom)
				(hide yes)
			)
		)
		(pin "2"
		)
		(pin "1"
		)
		(instances
			(project "com-express-7-baseboard"
				(path ""
					(reference "R294")
					(unit 1)
				)
				(path ""
					(reference "R260")
					(unit 1)
				)
			)
		)
	)
	(symbol
		(lib_id "antmicropower:GND")
		(at 297.18 170.18 0)
		(mirror y)
		(unit 1)
		(exclude_from_sim no)
		(in_bom yes)
		(on_board yes)
		(dnp no)
		(fields_autoplaced yes)
		(property "Reference" "#PWR0367"
			(at 297.18 176.53 0)
			(effects
				(font
					(size 1.27 1.27)
				)
				(justify left bottom)
				(hide yes)
			)
		)
		(property "Value" "GND"
			(at 297.18 175.26 0)
			(effects
				(font
					(size 1.27 1.27)
				)
			)
		)
		(property "Footprint" ""
			(at 297.18 170.18 0)
			(effects
				(font
					(size 1.27 1.27)
				)
				(justify left bottom)
				(hide yes)
			)
		)
		(property "Datasheet" ""
			(at 297.18 170.18 0)
			(effects
				(font
					(size 1.27 1.27)
				)
				(justify left bottom)
				(hide yes)
			)
		)
		(property "Description" ""
			(at 297.18 170.18 0)
			(effects
				(font
					(size 1.27 1.27)
				)
				(hide yes)
			)
		)
		(property "Author" "Antmicro"
			(at 288.29 177.8 0)
			(effects
				(font
					(size 1.27 1.27)
					(thickness 0.15)
				)
				(justify left bottom)
				(hide yes)
			)
		)
		(property "License" "Apache-2.0"
			(at 288.29 180.34 0)
			(effects
				(font
					(size 1.27 1.27)
					(thickness 0.15)
				)
				(justify left bottom)
				(hide yes)
			)
		)
		(pin "1"
		)
		(instances
			(project "com-express-7-baseboard"
				(path ""
					(reference "#PWR0418")
					(unit 1)
				)
				(path ""
					(reference "#PWR0367")
					(unit 1)
				)
			)
		)
	)
	(symbol
		(lib_id "antmicroCapacitors0402:C_100n_0402")
		(at 276.86 215.9 90)
		(unit 1)
		(exclude_from_sim no)
		(in_bom yes)
		(on_board yes)
		(dnp no)
		(fields_autoplaced yes)
		(property "Reference" "C159"
			(at 279.4 212.0836 90)
			(effects
				(font
					(size 1.27 1.27)
					(thickness 0.15)
				)
				(justify right)
			)
		)
		(property "Value" "C_100n_0402"
			(at 287.02 195.58 0)
			(effects
				(font
					(size 1.27 1.27)
					(thickness 0.15)
				)
				(justify left bottom)
				(hide yes)
			)
		)
		(property "Footprint" "antmicro-footprints:C_0402_1005Metric"
			(at 289.56 195.58 0)
			(effects
				(font
					(size 1.27 1.27)
					(thickness 0.15)
				)
				(justify left bottom)
				(hide yes)
			)
		)
		(property "Datasheet" "https://www.murata.com/products/productdetail?partno=GRM155R61H104KE14%23"
			(at 292.1 195.58 0)
			(effects
				(font
					(size 1.27 1.27)
					(thickness 0.15)
				)
				(justify left bottom)
				(hide yes)
			)
		)
		(property "Description" ""
			(at 276.86 215.9 0)
			(effects
				(font
					(size 1.27 1.27)
				)
				(hide yes)
			)
		)
		(property "MPN" "GRM155R61H104KE14D"
			(at 294.64 195.58 0)
			(effects
				(font
					(size 1.27 1.27)
					(thickness 0.15)
				)
				(justify left bottom)
				(hide yes)
			)
		)
		(property "Manufacturer" "Murata"
			(at 297.18 195.58 0)
			(effects
				(font
					(size 1.27 1.27)
					(thickness 0.15)
				)
				(justify left bottom)
				(hide yes)
			)
		)
		(property "License" "Apache-2.0"
			(at 299.72 195.58 0)
			(effects
				(font
					(size 1.27 1.27)
					(thickness 0.15)
				)
				(justify left bottom)
				(hide yes)
			)
		)
		(property "Author" "Antmicro"
			(at 302.26 195.58 0)
			(effects
				(font
					(size 1.27 1.27)
					(thickness 0.15)
				)
				(justify left bottom)
				(hide yes)
			)
		)
		(property "Val" "100n"
			(at 279.4 214.6236 90)
			(effects
				(font
					(size 1.27 1.27)
					(thickness 0.15)
				)
				(justify right)
			)
		)
		(property "Voltage" "50V"
			(at 304.8 195.58 0)
			(effects
				(font
					(size 1.27 1.27)
				)
				(justify left bottom)
				(hide yes)
			)
		)
		(property "Dielectric" "X5R"
			(at 307.34 195.58 0)
			(effects
				(font
					(size 1.27 1.27)
				)
				(justify left bottom)
				(hide yes)
			)
		)
		(property "Public" "False"
			(at 309.88 195.58 0)
			(effects
				(font
					(size 1.27 1.27)
				)
				(justify left bottom)
				(hide yes)
			)
		)
		(pin "2"
		)
		(pin "1"
		)
		(instances
			(project "com-express-7-baseboard"
				(path ""
					(reference "C186")
					(unit 1)
				)
				(path ""
					(reference "C159")
					(unit 1)
				)
			)
		)
	)
	(symbol
		(lib_id "antmicroResistors0402:R_0R_0402")
		(at 120.65 228.6 0)
		(unit 1)
		(exclude_from_sim no)
		(in_bom yes)
		(on_board yes)
		(dnp no)
		(property "Reference" "R247"
			(at 116.84 227.33 0)
			(effects
				(font
					(size 1.27 1.27)
					(thickness 0.15)
				)
			)
		)
		(property "Value" "R_0R_0402"
			(at 140.97 241.3 0)
			(effects
				(font
					(size 1.27 1.27)
					(thickness 0.15)
				)
				(justify left bottom)
				(hide yes)
			)
		)
		(property "Footprint" "antmicro-footprints:R_0402_1005Metric"
			(at 140.97 243.84 0)
			(effects
				(font
					(size 1.27 1.27)
					(thickness 0.15)
				)
				(justify left bottom)
				(hide yes)
			)
		)
		(property "Datasheet" "https://industrial.panasonic.com/cdbs/www-data/pdf/RDA0000/AOA0000C301.pdf"
			(at 140.97 246.38 0)
			(effects
				(font
					(size 1.27 1.27)
					(thickness 0.15)
				)
				(justify left bottom)
				(hide yes)
			)
		)
		(property "Description" ""
			(at 120.65 228.6 0)
			(effects
				(font
					(size 1.27 1.27)
				)
				(hide yes)
			)
		)
		(property "MPN" "ERJ2GE0R00X"
			(at 140.97 248.92 0)
			(effects
				(font
					(size 1.27 1.27)
					(thickness 0.15)
				)
				(justify left bottom)
				(hide yes)
			)
		)
		(property "Manufacturer" "Panasonic"
			(at 140.97 251.46 0)
			(effects
				(font
					(size 1.27 1.27)
					(thickness 0.15)
				)
				(justify left bottom)
				(hide yes)
			)
		)
		(property "License" "Apache-2.0"
			(at 140.97 254 0)
			(effects
				(font
					(size 1.27 1.27)
					(thickness 0.15)
				)
				(justify left bottom)
				(hide yes)
			)
		)
		(property "Author" "Antmicro"
			(at 140.97 256.54 0)
			(effects
				(font
					(size 1.27 1.27)
					(thickness 0.15)
				)
				(justify left bottom)
				(hide yes)
			)
		)
		(property "Val" "0R"
			(at 127 227.33 0)
			(effects
				(font
					(size 1.27 1.27)
					(thickness 0.15)
				)
			)
		)
		(property "Tolerance" "~"
			(at 140.97 238.76 0)
			(effects
				(font
					(size 1.27 1.27)
				)
				(justify left bottom)
				(hide yes)
			)
		)
		(property "Current" "1A"
			(at 140.97 259.08 0)
			(effects
				(font
					(size 1.27 1.27)
					(thickness 0.15)
				)
				(justify left bottom)
				(hide yes)
			)
		)
		(property "Public" "False"
			(at 140.97 259.08 0)
			(effects
				(font
					(size 1.27 1.27)
				)
				(justify left bottom)
				(hide yes)
			)
		)
		(pin "1"
		)
		(pin "2"
		)
		(instances
			(project "com-express-7-baseboard"
				(path ""
					(reference "R281")
					(unit 1)
				)
				(path ""
					(reference "R247")
					(unit 1)
				)
			)
		)
	)
	(symbol
		(lib_id "antmicropower:+1V8")
		(at 199.39 114.3 0)
		(unit 1)
		(exclude_from_sim no)
		(in_bom yes)
		(on_board yes)
		(dnp no)
		(property "Reference" "#PWR0344"
			(at 214.63 116.84 0)
			(effects
				(font
					(size 1.27 1.27)
					(thickness 0.15)
				)
				(justify left bottom)
				(hide yes)
			)
		)
		(property "Value" "+1V8"
			(at 199.39 110.49 0)
			(effects
				(font
					(size 1.27 1.27)
					(thickness 0.15)
				)
			)
		)
		(property "Footprint" ""
			(at 214.63 121.92 0)
			(effects
				(font
					(size 1.27 1.27)
					(thickness 0.15)
				)
				(justify left bottom)
				(hide yes)
			)
		)
		(property "Datasheet" ""
			(at 214.63 124.46 0)
			(effects
				(font
					(size 1.27 1.27)
					(thickness 0.15)
				)
				(justify left bottom)
				(hide yes)
			)
		)
		(property "Description" ""
			(at 199.39 114.3 0)
			(effects
				(font
					(size 1.27 1.27)
				)
				(hide yes)
			)
		)
		(property "Author" "Antmicro"
			(at 214.63 119.38 0)
			(effects
				(font
					(size 1.27 1.27)
					(thickness 0.15)
				)
				(justify left bottom)
				(hide yes)
			)
		)
		(property "License" "Apache-2.0"
			(at 214.63 121.92 0)
			(effects
				(font
					(size 1.27 1.27)
					(thickness 0.15)
				)
				(justify left bottom)
				(hide yes)
			)
		)
		(pin "1"
		)
		(instances
			(project "com-express-7-baseboard"
				(path ""
					(reference "#PWR0395")
					(unit 1)
				)
				(path ""
					(reference "#PWR0344")
					(unit 1)
				)
			)
		)
	)
	(symbol
		(lib_id "antmicroTestPoints:TP_0.75mm_SMD")
		(at 157.48 241.3 0)
		(mirror y)
		(unit 1)
		(exclude_from_sim no)
		(in_bom no)
		(on_board yes)
		(dnp no)
		(fields_autoplaced yes)
		(property "Reference" "TP65"
			(at 152.4 241.3 0)
			(effects
				(font
					(size 1.27 1.27)
					(thickness 0.15)
				)
				(justify left)
			)
		)
		(property "Value" "TP_0.75mm_SMD"
			(at 146.685 245.11 0)
			(effects
				(font
					(size 1.27 1.27)
					(thickness 0.15)
				)
				(justify left bottom)
				(hide yes)
			)
		)
		(property "Footprint" "antmicro-footprints:TP_SMD_0.75mm"
			(at 146.685 247.65 0)
			(effects
				(font
					(size 1.27 1.27)
					(thickness 0.15)
				)
				(justify left bottom)
				(hide yes)
			)
		)
		(property "Datasheet" ""
			(at 139.7 254 0)
			(effects
				(font
					(size 1.27 1.27)
					(thickness 0.15)
				)
				(justify left bottom)
				(hide yes)
			)
		)
		(property "Description" ""
			(at 157.48 241.3 0)
			(effects
				(font
					(size 1.27 1.27)
				)
				(hide yes)
			)
		)
		(property "MPN" ""
			(at 146.685 252.73 0)
			(effects
				(font
					(size 1.27 1.27)
					(thickness 0.15)
				)
				(justify left bottom)
				(hide yes)
			)
		)
		(property "Manufacturer" ""
			(at 146.685 247.65 0)
			(effects
				(font
					(size 1.27 1.27)
					(thickness 0.15)
				)
				(justify left bottom)
				(hide yes)
			)
		)
		(property "Author" "Antmicro"
			(at 146.685 250.19 0)
			(effects
				(font
					(size 1.27 1.27)
					(thickness 0.15)
				)
				(justify left bottom)
				(hide yes)
			)
		)
		(property "License" "Apache-2.0"
			(at 146.685 252.73 0)
			(effects
				(font
					(size 1.27 1.27)
					(thickness 0.15)
				)
				(justify left bottom)
				(hide yes)
			)
		)
		(property "Public" "False"
			(at 147.32 255.27 0)
			(effects
				(font
					(size 1.27 1.27)
				)
				(justify left bottom)
				(hide yes)
			)
		)
		(pin "1"
		)
		(instances
			(project "com-express-7-baseboard"
				(path ""
					(reference "TP85")
					(unit 1)
				)
				(path ""
					(reference "TP65")
					(unit 1)
				)
			)
		)
	)
	(symbol
		(lib_id "antmicropower:+1V8")
		(at 276.86 184.15 0)
		(unit 1)
		(exclude_from_sim no)
		(in_bom yes)
		(on_board yes)
		(dnp no)
		(property "Reference" "#PWR0357"
			(at 292.1 186.69 0)
			(effects
				(font
					(size 1.27 1.27)
					(thickness 0.15)
				)
				(justify left bottom)
				(hide yes)
			)
		)
		(property "Value" "+1V8"
			(at 276.86 180.34 0)
			(effects
				(font
					(size 1.27 1.27)
					(thickness 0.15)
				)
			)
		)
		(property "Footprint" ""
			(at 292.1 191.77 0)
			(effects
				(font
					(size 1.27 1.27)
					(thickness 0.15)
				)
				(justify left bottom)
				(hide yes)
			)
		)
		(property "Datasheet" ""
			(at 292.1 194.31 0)
			(effects
				(font
					(size 1.27 1.27)
					(thickness 0.15)
				)
				(justify left bottom)
				(hide yes)
			)
		)
		(property "Description" ""
			(at 276.86 184.15 0)
			(effects
				(font
					(size 1.27 1.27)
				)
				(hide yes)
			)
		)
		(property "Author" "Antmicro"
			(at 292.1 189.23 0)
			(effects
				(font
					(size 1.27 1.27)
					(thickness 0.15)
				)
				(justify left bottom)
				(hide yes)
			)
		)
		(property "License" "Apache-2.0"
			(at 292.1 191.77 0)
			(effects
				(font
					(size 1.27 1.27)
					(thickness 0.15)
				)
				(justify left bottom)
				(hide yes)
			)
		)
		(pin "1"
		)
		(instances
			(project "com-express-7-baseboard"
				(path ""
					(reference "#PWR0408")
					(unit 1)
				)
				(path ""
					(reference "#PWR0357")
					(unit 1)
				)
			)
		)
	)
	(symbol
		(lib_id "antmicropower:GND")
		(at 78.74 196.85 0)
		(mirror y)
		(unit 1)
		(exclude_from_sim no)
		(in_bom yes)
		(on_board yes)
		(dnp no)
		(property "Reference" "#PWR0331"
			(at 78.74 203.2 0)
			(effects
				(font
					(size 1.27 1.27)
				)
				(justify left bottom)
				(hide yes)
			)
		)
		(property "Value" "GND"
			(at 78.74 200.66 0)
			(effects
				(font
					(size 1.27 1.27)
				)
			)
		)
		(property "Footprint" ""
			(at 78.74 196.85 0)
			(effects
				(font
					(size 1.27 1.27)
				)
				(justify left bottom)
				(hide yes)
			)
		)
		(property "Datasheet" ""
			(at 78.74 196.85 0)
			(effects
				(font
					(size 1.27 1.27)
				)
				(justify left bottom)
				(hide yes)
			)
		)
		(property "Description" ""
			(at 78.74 196.85 0)
			(effects
				(font
					(size 1.27 1.27)
				)
				(hide yes)
			)
		)
		(property "Author" "Antmicro"
			(at 69.85 204.47 0)
			(effects
				(font
					(size 1.27 1.27)
					(thickness 0.15)
				)
				(justify left bottom)
				(hide yes)
			)
		)
		(property "License" "Apache-2.0"
			(at 69.85 207.01 0)
			(effects
				(font
					(size 1.27 1.27)
					(thickness 0.15)
				)
				(justify left bottom)
				(hide yes)
			)
		)
		(pin "1"
		)
		(instances
			(project "com-express-7-baseboard"
				(path ""
					(reference "#PWR0382")
					(unit 1)
				)
				(path ""
					(reference "#PWR0331")
					(unit 1)
				)
			)
		)
	)
	(symbol
		(lib_id "antmicroCapacitorsmisc:C_100n_0201_25V")
		(at 128.27 86.36 0)
		(unit 1)
		(exclude_from_sim no)
		(in_bom yes)
		(on_board yes)
		(dnp no)
		(property "Reference" "C154"
			(at 127 87.63 0)
			(effects
				(font
					(size 1.27 1.27)
					(thickness 0.15)
				)
			)
		)
		(property "Value" "C_100n_0201_25V"
			(at 148.59 96.52 0)
			(effects
				(font
					(size 1.27 1.27)
					(thickness 0.15)
				)
				(justify left bottom)
				(hide yes)
			)
		)
		(property "Footprint" "antmicro-footprints:C_0201"
			(at 148.59 99.06 0)
			(effects
				(font
					(size 1.27 1.27)
					(thickness 0.15)
				)
				(justify left bottom)
				(hide yes)
			)
		)
		(property "Datasheet" "https://product.tdk.com/en/search/capacitor/ceramic/mlcc/info?part_no=C0603X5R1E104K030BB"
			(at 148.59 101.6 0)
			(effects
				(font
					(size 1.27 1.27)
					(thickness 0.15)
				)
				(justify left bottom)
				(hide yes)
			)
		)
		(property "Description" ""
			(at 128.27 86.36 0)
			(effects
				(font
					(size 1.27 1.27)
				)
				(hide yes)
			)
		)
		(property "MPN" "C0603X5R1E104K030BB"
			(at 148.59 104.14 0)
			(effects
				(font
					(size 1.27 1.27)
					(thickness 0.15)
				)
				(justify left bottom)
				(hide yes)
			)
		)
		(property "Manufacturer" "TDK"
			(at 148.59 106.68 0)
			(effects
				(font
					(size 1.27 1.27)
					(thickness 0.15)
				)
				(justify left bottom)
				(hide yes)
			)
		)
		(property "License" "Apache-2.0"
			(at 148.59 109.22 0)
			(effects
				(font
					(size 1.27 1.27)
					(thickness 0.15)
				)
				(justify left bottom)
				(hide yes)
			)
		)
		(property "Author" "Antmicro"
			(at 148.59 111.76 0)
			(effects
				(font
					(size 1.27 1.27)
					(thickness 0.15)
				)
				(justify left bottom)
				(hide yes)
			)
		)
		(property "Val" "100n"
			(at 134.62 87.63 0)
			(effects
				(font
					(size 1.27 1.27)
					(thickness 0.15)
				)
			)
		)
		(property "Voltage" "25V"
			(at 148.59 114.3 0)
			(effects
				(font
					(size 1.27 1.27)
				)
				(justify left bottom)
				(hide yes)
			)
		)
		(property "Dielectric" ""
			(at 148.59 116.84 0)
			(effects
				(font
					(size 1.27 1.27)
				)
				(justify left bottom)
				(hide yes)
			)
		)
		(property "Public" "False"
			(at 148.59 119.38 0)
			(effects
				(font
					(size 1.27 1.27)
				)
				(justify left bottom)
				(hide yes)
			)
		)
		(pin "2"
		)
		(pin "1"
		)
		(instances
			(project "com-express-7-baseboard"
				(path ""
					(reference "C181")
					(unit 1)
				)
				(path ""
					(reference "C154")
					(unit 1)
				)
			)
		)
	)
	(symbol
		(lib_id "antmicroCapacitors0402:C_100n_0402")
		(at 287.02 170.18 90)
		(unit 1)
		(exclude_from_sim no)
		(in_bom yes)
		(on_board yes)
		(dnp no)
		(fields_autoplaced yes)
		(property "Reference" "C161"
			(at 289.56 166.3636 90)
			(effects
				(font
					(size 1.27 1.27)
					(thickness 0.15)
				)
				(justify right)
			)
		)
		(property "Value" "C_100n_0402"
			(at 297.18 149.86 0)
			(effects
				(font
					(size 1.27 1.27)
					(thickness 0.15)
				)
				(justify left bottom)
				(hide yes)
			)
		)
		(property "Footprint" "antmicro-footprints:C_0402_1005Metric"
			(at 299.72 149.86 0)
			(effects
				(font
					(size 1.27 1.27)
					(thickness 0.15)
				)
				(justify left bottom)
				(hide yes)
			)
		)
		(property "Datasheet" "https://www.murata.com/products/productdetail?partno=GRM155R61H104KE14%23"
			(at 302.26 149.86 0)
			(effects
				(font
					(size 1.27 1.27)
					(thickness 0.15)
				)
				(justify left bottom)
				(hide yes)
			)
		)
		(property "Description" ""
			(at 287.02 170.18 0)
			(effects
				(font
					(size 1.27 1.27)
				)
				(hide yes)
			)
		)
		(property "MPN" "GRM155R61H104KE14D"
			(at 304.8 149.86 0)
			(effects
				(font
					(size 1.27 1.27)
					(thickness 0.15)
				)
				(justify left bottom)
				(hide yes)
			)
		)
		(property "Manufacturer" "Murata"
			(at 307.34 149.86 0)
			(effects
				(font
					(size 1.27 1.27)
					(thickness 0.15)
				)
				(justify left bottom)
				(hide yes)
			)
		)
		(property "License" "Apache-2.0"
			(at 309.88 149.86 0)
			(effects
				(font
					(size 1.27 1.27)
					(thickness 0.15)
				)
				(justify left bottom)
				(hide yes)
			)
		)
		(property "Author" "Antmicro"
			(at 312.42 149.86 0)
			(effects
				(font
					(size 1.27 1.27)
					(thickness 0.15)
				)
				(justify left bottom)
				(hide yes)
			)
		)
		(property "Val" "100n"
			(at 289.56 168.9036 90)
			(effects
				(font
					(size 1.27 1.27)
					(thickness 0.15)
				)
				(justify right)
			)
		)
		(property "Voltage" "50V"
			(at 314.96 149.86 0)
			(effects
				(font
					(size 1.27 1.27)
				)
				(justify left bottom)
				(hide yes)
			)
		)
		(property "Dielectric" "X5R"
			(at 317.5 149.86 0)
			(effects
				(font
					(size 1.27 1.27)
				)
				(justify left bottom)
				(hide yes)
			)
		)
		(property "Public" "False"
			(at 320.04 149.86 0)
			(effects
				(font
					(size 1.27 1.27)
				)
				(justify left bottom)
				(hide yes)
			)
		)
		(pin "2"
		)
		(pin "1"
		)
		(instances
			(project "com-express-7-baseboard"
				(path ""
					(reference "C188")
					(unit 1)
				)
				(path ""
					(reference "C161")
					(unit 1)
				)
			)
		)
	)
	(symbol
		(lib_id "antmicroResistorsmisc:R_0R_0201")
		(at 314.96 67.31 90)
		(unit 1)
		(exclude_from_sim no)
		(in_bom yes)
		(on_board yes)
		(dnp yes)
		(property "Reference" "R279"
			(at 316.23 59.69 0)
			(effects
				(font
					(size 1.27 1.27)
					(thickness 0.15)
				)
			)
		)
		(property "Value" "R_0R_0201"
			(at 327.66 46.99 0)
			(effects
				(font
					(size 1.27 1.27)
					(thickness 0.15)
				)
				(justify left bottom)
				(hide yes)
			)
		)
		(property "Footprint" "antmicro-footprints:R_0201"
			(at 330.2 46.99 0)
			(effects
				(font
					(size 1.27 1.27)
					(thickness 0.15)
				)
				(justify left bottom)
				(hide yes)
			)
		)
		(property "Datasheet" "https://www.bourns.com/docs/product-datasheets/cr.pdf"
			(at 332.74 46.99 0)
			(effects
				(font
					(size 1.27 1.27)
					(thickness 0.15)
				)
				(justify left bottom)
				(hide yes)
			)
		)
		(property "Description" ""
			(at 314.96 67.31 0)
			(effects
				(font
					(size 1.27 1.27)
				)
				(hide yes)
			)
		)
		(property "MPN" "CR0201-FX-0R00GLF"
			(at 335.28 46.99 0)
			(effects
				(font
					(size 1.27 1.27)
					(thickness 0.15)
				)
				(justify left bottom)
				(hide yes)
			)
		)
		(property "Manufacturer" "Bourns"
			(at 337.82 46.99 0)
			(effects
				(font
					(size 1.27 1.27)
					(thickness 0.15)
				)
				(justify left bottom)
				(hide yes)
			)
		)
		(property "License" "Apache-2.0"
			(at 340.36 46.99 0)
			(effects
				(font
					(size 1.27 1.27)
					(thickness 0.15)
				)
				(justify left bottom)
				(hide yes)
			)
		)
		(property "Author" "Antmicro"
			(at 342.9 46.99 0)
			(effects
				(font
					(size 1.27 1.27)
					(thickness 0.15)
				)
				(justify left bottom)
				(hide yes)
			)
		)
		(property "Val" "0R"
			(at 316.23 68.58 0)
			(effects
				(font
					(size 1.27 1.27)
					(thickness 0.15)
				)
			)
		)
		(property "Tolerance" "1%"
			(at 325.12 46.99 0)
			(effects
				(font
					(size 1.27 1.27)
				)
				(justify left bottom)
				(hide yes)
			)
		)
		(pin "1"
		)
		(pin "2"
		)
		(instances
			(project "com-express-7-baseboard"
				(path ""
					(reference "R313")
					(unit 1)
				)
				(path ""
					(reference "R279")
					(unit 1)
				)
			)
		)
	)
	(symbol
		(lib_id "antmicroResistorsmisc:R_0R_0201")
		(at 283.21 83.82 0)
		(unit 1)
		(exclude_from_sim no)
		(in_bom yes)
		(on_board yes)
		(dnp no)
		(property "Reference" "R273"
			(at 280.67 82.55 0)
			(effects
				(font
					(size 1.27 1.27)
					(thickness 0.15)
				)
			)
		)
		(property "Value" "R_0R_0201"
			(at 303.53 96.52 0)
			(effects
				(font
					(size 1.27 1.27)
					(thickness 0.15)
				)
				(justify left bottom)
				(hide yes)
			)
		)
		(property "Footprint" "antmicro-footprints:R_0201"
			(at 303.53 99.06 0)
			(effects
				(font
					(size 1.27 1.27)
					(thickness 0.15)
				)
				(justify left bottom)
				(hide yes)
			)
		)
		(property "Datasheet" "https://www.bourns.com/docs/product-datasheets/cr.pdf"
			(at 303.53 101.6 0)
			(effects
				(font
					(size 1.27 1.27)
					(thickness 0.15)
				)
				(justify left bottom)
				(hide yes)
			)
		)
		(property "Description" ""
			(at 283.21 83.82 0)
			(effects
				(font
					(size 1.27 1.27)
				)
				(hide yes)
			)
		)
		(property "MPN" "CR0201-FX-0R00GLF"
			(at 303.53 104.14 0)
			(effects
				(font
					(size 1.27 1.27)
					(thickness 0.15)
				)
				(justify left bottom)
				(hide yes)
			)
		)
		(property "Manufacturer" "Bourns"
			(at 303.53 106.68 0)
			(effects
				(font
					(size 1.27 1.27)
					(thickness 0.15)
				)
				(justify left bottom)
				(hide yes)
			)
		)
		(property "License" "Apache-2.0"
			(at 303.53 109.22 0)
			(effects
				(font
					(size 1.27 1.27)
					(thickness 0.15)
				)
				(justify left bottom)
				(hide yes)
			)
		)
		(property "Author" "Antmicro"
			(at 303.53 111.76 0)
			(effects
				(font
					(size 1.27 1.27)
					(thickness 0.15)
				)
				(justify left bottom)
				(hide yes)
			)
		)
		(property "Val" "0R"
			(at 289.56 82.55 0)
			(effects
				(font
					(size 1.27 1.27)
					(thickness 0.15)
				)
			)
		)
		(property "Tolerance" "1%"
			(at 303.53 93.98 0)
			(effects
				(font
					(size 1.27 1.27)
				)
				(justify left bottom)
				(hide yes)
			)
		)
		(pin "1"
		)
		(pin "2"
		)
		(instances
			(project "com-express-7-baseboard"
				(path ""
					(reference "R307")
					(unit 1)
				)
				(path ""
					(reference "R273")
					(unit 1)
				)
			)
		)
	)
	(symbol
		(lib_id "antmicropower:GND")
		(at 74.93 219.71 0)
		(mirror y)
		(unit 1)
		(exclude_from_sim no)
		(in_bom yes)
		(on_board yes)
		(dnp no)
		(property "Reference" "#PWR0330"
			(at 74.93 226.06 0)
			(effects
				(font
					(size 1.27 1.27)
				)
				(justify left bottom)
				(hide yes)
			)
		)
		(property "Value" "GND"
			(at 74.93 223.52 0)
			(effects
				(font
					(size 1.27 1.27)
				)
			)
		)
		(property "Footprint" ""
			(at 74.93 219.71 0)
			(effects
				(font
					(size 1.27 1.27)
				)
				(justify left bottom)
				(hide yes)
			)
		)
		(property "Datasheet" ""
			(at 74.93 219.71 0)
			(effects
				(font
					(size 1.27 1.27)
				)
				(justify left bottom)
				(hide yes)
			)
		)
		(property "Description" ""
			(at 74.93 219.71 0)
			(effects
				(font
					(size 1.27 1.27)
				)
				(hide yes)
			)
		)
		(property "Author" "Antmicro"
			(at 66.04 227.33 0)
			(effects
				(font
					(size 1.27 1.27)
					(thickness 0.15)
				)
				(justify left bottom)
				(hide yes)
			)
		)
		(property "License" "Apache-2.0"
			(at 66.04 229.87 0)
			(effects
				(font
					(size 1.27 1.27)
					(thickness 0.15)
				)
				(justify left bottom)
				(hide yes)
			)
		)
		(pin "1"
		)
		(instances
			(project "com-express-7-baseboard"
				(path ""
					(reference "#PWR0381")
					(unit 1)
				)
				(path ""
					(reference "#PWR0330")
					(unit 1)
				)
			)
		)
	)
	(symbol
		(lib_id "antmicropower:GND")
		(at 132.08 248.92 0)
		(mirror y)
		(unit 1)
		(exclude_from_sim no)
		(in_bom yes)
		(on_board yes)
		(dnp no)
		(fields_autoplaced yes)
		(property "Reference" "#PWR0337"
			(at 132.08 255.27 0)
			(effects
				(font
					(size 1.27 1.27)
				)
				(justify left bottom)
				(hide yes)
			)
		)
		(property "Value" "GND"
			(at 132.08 254 0)
			(effects
				(font
					(size 1.27 1.27)
				)
			)
		)
		(property "Footprint" ""
			(at 132.08 248.92 0)
			(effects
				(font
					(size 1.27 1.27)
				)
				(justify left bottom)
				(hide yes)
			)
		)
		(property "Datasheet" ""
			(at 132.08 248.92 0)
			(effects
				(font
					(size 1.27 1.27)
				)
				(justify left bottom)
				(hide yes)
			)
		)
		(property "Description" ""
			(at 132.08 248.92 0)
			(effects
				(font
					(size 1.27 1.27)
				)
				(hide yes)
			)
		)
		(property "Author" "Antmicro"
			(at 123.19 256.54 0)
			(effects
				(font
					(size 1.27 1.27)
					(thickness 0.15)
				)
				(justify left bottom)
				(hide yes)
			)
		)
		(property "License" "Apache-2.0"
			(at 123.19 259.08 0)
			(effects
				(font
					(size 1.27 1.27)
					(thickness 0.15)
				)
				(justify left bottom)
				(hide yes)
			)
		)
		(pin "1"
		)
		(instances
			(project "com-express-7-baseboard"
				(path ""
					(reference "#PWR0388")
					(unit 1)
				)
				(path ""
					(reference "#PWR0337")
					(unit 1)
				)
			)
		)
	)
	(symbol
		(lib_id "antmicropower:GND")
		(at 261.62 190.5 0)
		(mirror y)
		(unit 1)
		(exclude_from_sim no)
		(in_bom yes)
		(on_board yes)
		(dnp no)
		(fields_autoplaced yes)
		(property "Reference" "#PWR0352"
			(at 261.62 196.85 0)
			(effects
				(font
					(size 1.27 1.27)
				)
				(justify left bottom)
				(hide yes)
			)
		)
		(property "Value" "GND"
			(at 261.62 195.58 0)
			(effects
				(font
					(size 1.27 1.27)
				)
			)
		)
		(property "Footprint" ""
			(at 261.62 190.5 0)
			(effects
				(font
					(size 1.27 1.27)
				)
				(justify left bottom)
				(hide yes)
			)
		)
		(property "Datasheet" ""
			(at 261.62 190.5 0)
			(effects
				(font
					(size 1.27 1.27)
				)
				(justify left bottom)
				(hide yes)
			)
		)
		(property "Description" ""
			(at 261.62 190.5 0)
			(effects
				(font
					(size 1.27 1.27)
				)
				(hide yes)
			)
		)
		(property "Author" "Antmicro"
			(at 252.73 198.12 0)
			(effects
				(font
					(size 1.27 1.27)
					(thickness 0.15)
				)
				(justify left bottom)
				(hide yes)
			)
		)
		(property "License" "Apache-2.0"
			(at 252.73 200.66 0)
			(effects
				(font
					(size 1.27 1.27)
					(thickness 0.15)
				)
				(justify left bottom)
				(hide yes)
			)
		)
		(pin "1"
		)
		(instances
			(project "com-express-7-baseboard"
				(path ""
					(reference "#PWR0403")
					(unit 1)
				)
				(path ""
					(reference "#PWR0352")
					(unit 1)
				)
			)
		)
	)
	(symbol
		(lib_id "antmicroResistorsmisc:R_0R_0201")
		(at 283.21 76.2 0)
		(unit 1)
		(exclude_from_sim no)
		(in_bom yes)
		(on_board yes)
		(dnp no)
		(property "Reference" "R272"
			(at 280.67 74.93 0)
			(effects
				(font
					(size 1.27 1.27)
					(thickness 0.15)
				)
			)
		)
		(property "Value" "R_0R_0201"
			(at 303.53 88.9 0)
			(effects
				(font
					(size 1.27 1.27)
					(thickness 0.15)
				)
				(justify left bottom)
				(hide yes)
			)
		)
		(property "Footprint" "antmicro-footprints:R_0201"
			(at 303.53 91.44 0)
			(effects
				(font
					(size 1.27 1.27)
					(thickness 0.15)
				)
				(justify left bottom)
				(hide yes)
			)
		)
		(property "Datasheet" "https://www.bourns.com/docs/product-datasheets/cr.pdf"
			(at 303.53 93.98 0)
			(effects
				(font
					(size 1.27 1.27)
					(thickness 0.15)
				)
				(justify left bottom)
				(hide yes)
			)
		)
		(property "Description" ""
			(at 283.21 76.2 0)
			(effects
				(font
					(size 1.27 1.27)
				)
				(hide yes)
			)
		)
		(property "MPN" "CR0201-FX-0R00GLF"
			(at 303.53 96.52 0)
			(effects
				(font
					(size 1.27 1.27)
					(thickness 0.15)
				)
				(justify left bottom)
				(hide yes)
			)
		)
		(property "Manufacturer" "Bourns"
			(at 303.53 99.06 0)
			(effects
				(font
					(size 1.27 1.27)
					(thickness 0.15)
				)
				(justify left bottom)
				(hide yes)
			)
		)
		(property "License" "Apache-2.0"
			(at 303.53 101.6 0)
			(effects
				(font
					(size 1.27 1.27)
					(thickness 0.15)
				)
				(justify left bottom)
				(hide yes)
			)
		)
		(property "Author" "Antmicro"
			(at 303.53 104.14 0)
			(effects
				(font
					(size 1.27 1.27)
					(thickness 0.15)
				)
				(justify left bottom)
				(hide yes)
			)
		)
		(property "Val" "0R"
			(at 289.56 74.93 0)
			(effects
				(font
					(size 1.27 1.27)
					(thickness 0.15)
				)
			)
		)
		(property "Tolerance" "1%"
			(at 303.53 86.36 0)
			(effects
				(font
					(size 1.27 1.27)
				)
				(justify left bottom)
				(hide yes)
			)
		)
		(pin "1"
		)
		(pin "2"
		)
		(instances
			(project "com-express-7-baseboard"
				(path ""
					(reference "R306")
					(unit 1)
				)
				(path ""
					(reference "R272")
					(unit 1)
				)
			)
		)
	)
	(symbol
		(lib_id "antmicroCapacitorsmisc:C_100n_0201_25V")
		(at 124.46 83.82 0)
		(unit 1)
		(exclude_from_sim no)
		(in_bom yes)
		(on_board yes)
		(dnp no)
		(property "Reference" "C153"
			(at 123.19 82.55 0)
			(effects
				(font
					(size 1.27 1.27)
					(thickness 0.15)
				)
			)
		)
		(property "Value" "C_100n_0201_25V"
			(at 144.78 93.98 0)
			(effects
				(font
					(size 1.27 1.27)
					(thickness 0.15)
				)
				(justify left bottom)
				(hide yes)
			)
		)
		(property "Footprint" "antmicro-footprints:C_0201"
			(at 144.78 96.52 0)
			(effects
				(font
					(size 1.27 1.27)
					(thickness 0.15)
				)
				(justify left bottom)
				(hide yes)
			)
		)
		(property "Datasheet" "https://product.tdk.com/en/search/capacitor/ceramic/mlcc/info?part_no=C0603X5R1E104K030BB"
			(at 144.78 99.06 0)
			(effects
				(font
					(size 1.27 1.27)
					(thickness 0.15)
				)
				(justify left bottom)
				(hide yes)
			)
		)
		(property "Description" ""
			(at 124.46 83.82 0)
			(effects
				(font
					(size 1.27 1.27)
				)
				(hide yes)
			)
		)
		(property "MPN" "C0603X5R1E104K030BB"
			(at 144.78 101.6 0)
			(effects
				(font
					(size 1.27 1.27)
					(thickness 0.15)
				)
				(justify left bottom)
				(hide yes)
			)
		)
		(property "Manufacturer" "TDK"
			(at 144.78 104.14 0)
			(effects
				(font
					(size 1.27 1.27)
					(thickness 0.15)
				)
				(justify left bottom)
				(hide yes)
			)
		)
		(property "License" "Apache-2.0"
			(at 144.78 106.68 0)
			(effects
				(font
					(size 1.27 1.27)
					(thickness 0.15)
				)
				(justify left bottom)
				(hide yes)
			)
		)
		(property "Author" "Antmicro"
			(at 144.78 109.22 0)
			(effects
				(font
					(size 1.27 1.27)
					(thickness 0.15)
				)
				(justify left bottom)
				(hide yes)
			)
		)
		(property "Val" "100n"
			(at 130.81 82.55 0)
			(effects
				(font
					(size 1.27 1.27)
					(thickness 0.15)
				)
			)
		)
		(property "Voltage" "25V"
			(at 144.78 111.76 0)
			(effects
				(font
					(size 1.27 1.27)
				)
				(justify left bottom)
				(hide yes)
			)
		)
		(property "Dielectric" ""
			(at 144.78 114.3 0)
			(effects
				(font
					(size 1.27 1.27)
				)
				(justify left bottom)
				(hide yes)
			)
		)
		(property "Public" "False"
			(at 144.78 116.84 0)
			(effects
				(font
					(size 1.27 1.27)
				)
				(justify left bottom)
				(hide yes)
			)
		)
		(pin "2"
		)
		(pin "1"
		)
		(instances
			(project "com-express-7-baseboard"
				(path ""
					(reference "C180")
					(unit 1)
				)
				(path ""
					(reference "C153")
					(unit 1)
				)
			)
		)
	)
	(symbol
		(lib_id "antmicroCapacitors0402:C_100n_0402")
		(at 74.93 218.44 90)
		(unit 1)
		(exclude_from_sim no)
		(in_bom yes)
		(on_board yes)
		(dnp no)
		(fields_autoplaced yes)
		(property "Reference" "C149"
			(at 72.39 214.6235 90)
			(effects
				(font
					(size 1.27 1.27)
				)
				(justify left)
			)
		)
		(property "Value" "C_100n_0402"
			(at 78.74 218.44 0)
			(effects
				(font
					(size 1.27 1.27)
				)
				(justify left bottom)
				(hide yes)
			)
		)
		(property "Footprint" "antmicro-footprints:C_0402_1005Metric"
			(at 69.85 213.36 0)
			(effects
				(font
					(size 1.524 1.524)
				)
				(justify left bottom)
				(hide yes)
			)
		)
		(property "Datasheet" "https://www.murata.com/products/productdetail?partno=GRM155R61H104KE14%23"
			(at 74.93 218.44 0)
			(effects
				(font
					(size 1.27 1.27)
				)
				(justify left bottom)
				(hide yes)
			)
		)
		(property "Description" ""
			(at 74.93 218.44 0)
			(effects
				(font
					(size 1.27 1.27)
				)
				(hide yes)
			)
		)
		(property "Manufacturer" "Murata"
			(at 64.77 213.36 0)
			(effects
				(font
					(size 1.524 1.524)
				)
				(justify left bottom)
				(hide yes)
			)
		)
		(property "MPN" "GRM155R61H104KE14D"
			(at 67.31 213.36 0)
			(effects
				(font
					(size 1.524 1.524)
				)
				(justify left bottom)
				(hide yes)
			)
		)
		(property "Val" "100n"
			(at 72.39 217.1635 90)
			(effects
				(font
					(size 1.27 1.27)
				)
				(justify left)
			)
		)
		(property "License" "Apache-2.0"
			(at 97.79 198.12 0)
			(effects
				(font
					(size 1.27 1.27)
					(thickness 0.15)
				)
				(justify left bottom)
				(hide yes)
			)
		)
		(property "Author" "Antmicro"
			(at 100.33 198.12 0)
			(effects
				(font
					(size 1.27 1.27)
					(thickness 0.15)
				)
				(justify left bottom)
				(hide yes)
			)
		)
		(property "Voltage" "50V"
			(at 102.87 198.12 0)
			(effects
				(font
					(size 1.27 1.27)
				)
				(justify left bottom)
				(hide yes)
			)
		)
		(property "Dielectric" "X5R"
			(at 105.41 198.12 0)
			(effects
				(font
					(size 1.27 1.27)
				)
				(justify left bottom)
				(hide yes)
			)
		)
		(property "Public" "False"
			(at 107.95 198.12 0)
			(effects
				(font
					(size 1.27 1.27)
				)
				(justify left bottom)
				(hide yes)
			)
		)
		(pin "1"
		)
		(pin "2"
		)
		(instances
			(project "com-express-7-baseboard"
				(path ""
					(reference "C176")
					(unit 1)
				)
				(path ""
					(reference "C149")
					(unit 1)
				)
			)
		)
	)
	(symbol
		(lib_id "antmicroResistors0402:R_10k_0402")
		(at 132.08 248.92 90)
		(unit 1)
		(exclude_from_sim no)
		(in_bom yes)
		(on_board yes)
		(dnp no)
		(property "Reference" "R255"
			(at 133.35 245.11 90)
			(effects
				(font
					(size 1.27 1.27)
					(thickness 0.15)
				)
				(justify right)
			)
		)
		(property "Value" "R_10k_0402"
			(at 144.78 228.6 0)
			(effects
				(font
					(size 1.27 1.27)
					(thickness 0.15)
				)
				(justify left bottom)
				(hide yes)
			)
		)
		(property "Footprint" "antmicro-footprints:R_0402_1005Metric"
			(at 147.32 228.6 0)
			(effects
				(font
					(size 1.27 1.27)
					(thickness 0.15)
				)
				(justify left bottom)
				(hide yes)
			)
		)
		(property "Datasheet" "https://www.bourns.com/docs/product-datasheets/cr.pdf"
			(at 149.86 228.6 0)
			(effects
				(font
					(size 1.27 1.27)
					(thickness 0.15)
				)
				(justify left bottom)
				(hide yes)
			)
		)
		(property "Description" ""
			(at 132.08 248.92 0)
			(effects
				(font
					(size 1.27 1.27)
				)
				(hide yes)
			)
		)
		(property "MPN" "CR0402-FX-1002GLF"
			(at 152.4 228.6 0)
			(effects
				(font
					(size 1.27 1.27)
					(thickness 0.15)
				)
				(justify left bottom)
				(hide yes)
			)
		)
		(property "Manufacturer" "Bourns"
			(at 154.94 228.6 0)
			(effects
				(font
					(size 1.27 1.27)
					(thickness 0.15)
				)
				(justify left bottom)
				(hide yes)
			)
		)
		(property "License" "Apache-2.0"
			(at 157.48 228.6 0)
			(effects
				(font
					(size 1.27 1.27)
					(thickness 0.15)
				)
				(justify left bottom)
				(hide yes)
			)
		)
		(property "Author" "Antmicro"
			(at 160.02 228.6 0)
			(effects
				(font
					(size 1.27 1.27)
					(thickness 0.15)
				)
				(justify left bottom)
				(hide yes)
			)
		)
		(property "Val" "10k"
			(at 133.35 247.65 90)
			(effects
				(font
					(size 1.27 1.27)
					(thickness 0.15)
				)
				(justify right)
			)
		)
		(property "Tolerance" "1%"
			(at 142.24 228.6 0)
			(effects
				(font
					(size 1.27 1.27)
				)
				(justify left bottom)
				(hide yes)
			)
		)
		(property "Public" "False"
			(at 162.56 228.6 0)
			(effects
				(font
					(size 1.27 1.27)
				)
				(justify left bottom)
				(hide yes)
			)
		)
		(pin "2"
		)
		(pin "1"
		)
		(instances
			(project "com-express-7-baseboard"
				(path ""
					(reference "R289")
					(unit 1)
				)
				(path ""
					(reference "R255")
					(unit 1)
				)
			)
		)
	)
	(symbol
		(lib_id "antmicroCapacitors0402:C_100n_0402")
		(at 297.18 215.9 90)
		(unit 1)
		(exclude_from_sim no)
		(in_bom yes)
		(on_board yes)
		(dnp no)
		(fields_autoplaced yes)
		(property "Reference" "C167"
			(at 299.72 212.0836 90)
			(effects
				(font
					(size 1.27 1.27)
					(thickness 0.15)
				)
				(justify right)
			)
		)
		(property "Value" "C_100n_0402"
			(at 307.34 195.58 0)
			(effects
				(font
					(size 1.27 1.27)
					(thickness 0.15)
				)
				(justify left bottom)
				(hide yes)
			)
		)
		(property "Footprint" "antmicro-footprints:C_0402_1005Metric"
			(at 309.88 195.58 0)
			(effects
				(font
					(size 1.27 1.27)
					(thickness 0.15)
				)
				(justify left bottom)
				(hide yes)
			)
		)
		(property "Datasheet" "https://www.murata.com/products/productdetail?partno=GRM155R61H104KE14%23"
			(at 312.42 195.58 0)
			(effects
				(font
					(size 1.27 1.27)
					(thickness 0.15)
				)
				(justify left bottom)
				(hide yes)
			)
		)
		(property "Description" ""
			(at 297.18 215.9 0)
			(effects
				(font
					(size 1.27 1.27)
				)
				(hide yes)
			)
		)
		(property "MPN" "GRM155R61H104KE14D"
			(at 314.96 195.58 0)
			(effects
				(font
					(size 1.27 1.27)
					(thickness 0.15)
				)
				(justify left bottom)
				(hide yes)
			)
		)
		(property "Manufacturer" "Murata"
			(at 317.5 195.58 0)
			(effects
				(font
					(size 1.27 1.27)
					(thickness 0.15)
				)
				(justify left bottom)
				(hide yes)
			)
		)
		(property "License" "Apache-2.0"
			(at 320.04 195.58 0)
			(effects
				(font
					(size 1.27 1.27)
					(thickness 0.15)
				)
				(justify left bottom)
				(hide yes)
			)
		)
		(property "Author" "Antmicro"
			(at 322.58 195.58 0)
			(effects
				(font
					(size 1.27 1.27)
					(thickness 0.15)
				)
				(justify left bottom)
				(hide yes)
			)
		)
		(property "Val" "100n"
			(at 299.72 214.6236 90)
			(effects
				(font
					(size 1.27 1.27)
					(thickness 0.15)
				)
				(justify right)
			)
		)
		(property "Voltage" "50V"
			(at 325.12 195.58 0)
			(effects
				(font
					(size 1.27 1.27)
				)
				(justify left bottom)
				(hide yes)
			)
		)
		(property "Dielectric" "X5R"
			(at 327.66 195.58 0)
			(effects
				(font
					(size 1.27 1.27)
				)
				(justify left bottom)
				(hide yes)
			)
		)
		(property "Public" "False"
			(at 330.2 195.58 0)
			(effects
				(font
					(size 1.27 1.27)
				)
				(justify left bottom)
				(hide yes)
			)
		)
		(pin "2"
		)
		(pin "1"
		)
		(instances
			(project "com-express-7-baseboard"
				(path ""
					(reference "C194")
					(unit 1)
				)
				(path ""
					(reference "C167")
					(unit 1)
				)
			)
		)
	)
	(symbol
		(lib_id "antmicroCapacitors0603:C_22u_16V_0603")
		(at 261.62 208.28 90)
		(unit 1)
		(exclude_from_sim no)
		(in_bom yes)
		(on_board yes)
		(dnp no)
		(fields_autoplaced yes)
		(property "Reference" "C156"
			(at 264.16 204.4635 90)
			(effects
				(font
					(size 1.27 1.27)
					(thickness 0.15)
				)
				(justify right)
			)
		)
		(property "Value" "C_22u_16V_0603"
			(at 271.78 187.96 0)
			(effects
				(font
					(size 1.27 1.27)
					(thickness 0.15)
				)
				(justify left bottom)
				(hide yes)
			)
		)
		(property "Footprint" "antmicro-footprints:C_0603_1608Metric"
			(at 274.32 187.96 0)
			(effects
				(font
					(size 1.27 1.27)
					(thickness 0.15)
				)
				(justify left bottom)
				(hide yes)
			)
		)
		(property "Datasheet" "https://product.samsungsem.com/mlcc/CL10A226MO7JZN.do"
			(at 276.86 187.96 0)
			(effects
				(font
					(size 1.27 1.27)
					(thickness 0.15)
				)
				(justify left bottom)
				(hide yes)
			)
		)
		(property "Description" ""
			(at 261.62 208.28 0)
			(effects
				(font
					(size 1.27 1.27)
				)
				(hide yes)
			)
		)
		(property "MPN" "CL10A226MO7JZNC"
			(at 279.4 187.96 0)
			(effects
				(font
					(size 1.27 1.27)
					(thickness 0.15)
				)
				(justify left bottom)
				(hide yes)
			)
		)
		(property "Manufacturer" "Samsung Electro-Mechanics"
			(at 281.94 187.96 0)
			(effects
				(font
					(size 1.27 1.27)
					(thickness 0.15)
				)
				(justify left bottom)
				(hide yes)
			)
		)
		(property "License" "Apache-2.0"
			(at 284.48 187.96 0)
			(effects
				(font
					(size 1.27 1.27)
					(thickness 0.15)
				)
				(justify left bottom)
				(hide yes)
			)
		)
		(property "Author" "Antmicro"
			(at 287.02 187.96 0)
			(effects
				(font
					(size 1.27 1.27)
					(thickness 0.15)
				)
				(justify left bottom)
				(hide yes)
			)
		)
		(property "Val" "22u"
			(at 264.16 207.0035 90)
			(effects
				(font
					(size 1.27 1.27)
					(thickness 0.15)
				)
				(justify right)
			)
		)
		(property "Voltage" "16V"
			(at 289.56 187.96 0)
			(effects
				(font
					(size 1.27 1.27)
				)
				(justify left bottom)
				(hide yes)
			)
		)
		(property "Dielectric" ""
			(at 292.1 187.96 0)
			(effects
				(font
					(size 1.27 1.27)
				)
				(justify left bottom)
				(hide yes)
			)
		)
		(property "Public" "False"
			(at 294.64 187.96 0)
			(effects
				(font
					(size 1.27 1.27)
				)
				(justify left bottom)
				(hide yes)
			)
		)
		(pin "1"
		)
		(pin "2"
		)
		(instances
			(project "com-express-7-baseboard"
				(path ""
					(reference "C183")
					(unit 1)
				)
				(path ""
					(reference "C156")
					(unit 1)
				)
			)
		)
	)
	(symbol
		(lib_id "antmicroResistors0402:R_10k_0402")
		(at 200.66 250.19 90)
		(unit 1)
		(exclude_from_sim no)
		(in_bom yes)
		(on_board yes)
		(dnp no)
		(property "Reference" "R263"
			(at 201.93 246.38 90)
			(effects
				(font
					(size 1.27 1.27)
					(thickness 0.15)
				)
				(justify right)
			)
		)
		(property "Value" "R_10k_0402"
			(at 213.36 229.87 0)
			(effects
				(font
					(size 1.27 1.27)
					(thickness 0.15)
				)
				(justify left bottom)
				(hide yes)
			)
		)
		(property "Footprint" "antmicro-footprints:R_0402_1005Metric"
			(at 215.9 229.87 0)
			(effects
				(font
					(size 1.27 1.27)
					(thickness 0.15)
				)
				(justify left bottom)
				(hide yes)
			)
		)
		(property "Datasheet" "https://www.bourns.com/docs/product-datasheets/cr.pdf"
			(at 218.44 229.87 0)
			(effects
				(font
					(size 1.27 1.27)
					(thickness 0.15)
				)
				(justify left bottom)
				(hide yes)
			)
		)
		(property "Description" ""
			(at 200.66 250.19 0)
			(effects
				(font
					(size 1.27 1.27)
				)
				(hide yes)
			)
		)
		(property "MPN" "CR0402-FX-1002GLF"
			(at 220.98 229.87 0)
			(effects
				(font
					(size 1.27 1.27)
					(thickness 0.15)
				)
				(justify left bottom)
				(hide yes)
			)
		)
		(property "Manufacturer" "Bourns"
			(at 223.52 229.87 0)
			(effects
				(font
					(size 1.27 1.27)
					(thickness 0.15)
				)
				(justify left bottom)
				(hide yes)
			)
		)
		(property "License" "Apache-2.0"
			(at 226.06 229.87 0)
			(effects
				(font
					(size 1.27 1.27)
					(thickness 0.15)
				)
				(justify left bottom)
				(hide yes)
			)
		)
		(property "Author" "Antmicro"
			(at 228.6 229.87 0)
			(effects
				(font
					(size 1.27 1.27)
					(thickness 0.15)
				)
				(justify left bottom)
				(hide yes)
			)
		)
		(property "Val" "10k"
			(at 201.93 248.92 90)
			(effects
				(font
					(size 1.27 1.27)
					(thickness 0.15)
				)
				(justify right)
			)
		)
		(property "Tolerance" "1%"
			(at 210.82 229.87 0)
			(effects
				(font
					(size 1.27 1.27)
				)
				(justify left bottom)
				(hide yes)
			)
		)
		(property "Public" "False"
			(at 231.14 229.87 0)
			(effects
				(font
					(size 1.27 1.27)
				)
				(justify left bottom)
				(hide yes)
			)
		)
		(pin "2"
		)
		(pin "1"
		)
		(instances
			(project "com-express-7-baseboard"
				(path ""
					(reference "R297")
					(unit 1)
				)
				(path ""
					(reference "R263")
					(unit 1)
				)
			)
		)
	)
	(symbol
		(lib_id "antmicroCapacitors0402:C_100n_0402")
		(at 317.5 170.18 90)
		(unit 1)
		(exclude_from_sim no)
		(in_bom yes)
		(on_board yes)
		(dnp no)
		(fields_autoplaced yes)
		(property "Reference" "C171"
			(at 320.04 166.3636 90)
			(effects
				(font
					(size 1.27 1.27)
					(thickness 0.15)
				)
				(justify right)
			)
		)
		(property "Value" "C_100n_0402"
			(at 327.66 149.86 0)
			(effects
				(font
					(size 1.27 1.27)
					(thickness 0.15)
				)
				(justify left bottom)
				(hide yes)
			)
		)
		(property "Footprint" "antmicro-footprints:C_0402_1005Metric"
			(at 330.2 149.86 0)
			(effects
				(font
					(size 1.27 1.27)
					(thickness 0.15)
				)
				(justify left bottom)
				(hide yes)
			)
		)
		(property "Datasheet" "https://www.murata.com/products/productdetail?partno=GRM155R61H104KE14%23"
			(at 332.74 149.86 0)
			(effects
				(font
					(size 1.27 1.27)
					(thickness 0.15)
				)
				(justify left bottom)
				(hide yes)
			)
		)
		(property "Description" ""
			(at 317.5 170.18 0)
			(effects
				(font
					(size 1.27 1.27)
				)
				(hide yes)
			)
		)
		(property "MPN" "GRM155R61H104KE14D"
			(at 335.28 149.86 0)
			(effects
				(font
					(size 1.27 1.27)
					(thickness 0.15)
				)
				(justify left bottom)
				(hide yes)
			)
		)
		(property "Manufacturer" "Murata"
			(at 337.82 149.86 0)
			(effects
				(font
					(size 1.27 1.27)
					(thickness 0.15)
				)
				(justify left bottom)
				(hide yes)
			)
		)
		(property "License" "Apache-2.0"
			(at 340.36 149.86 0)
			(effects
				(font
					(size 1.27 1.27)
					(thickness 0.15)
				)
				(justify left bottom)
				(hide yes)
			)
		)
		(property "Author" "Antmicro"
			(at 342.9 149.86 0)
			(effects
				(font
					(size 1.27 1.27)
					(thickness 0.15)
				)
				(justify left bottom)
				(hide yes)
			)
		)
		(property "Val" "100n"
			(at 320.04 168.9036 90)
			(effects
				(font
					(size 1.27 1.27)
					(thickness 0.15)
				)
				(justify right)
			)
		)
		(property "Voltage" "50V"
			(at 345.44 149.86 0)
			(effects
				(font
					(size 1.27 1.27)
				)
				(justify left bottom)
				(hide yes)
			)
		)
		(property "Dielectric" "X5R"
			(at 347.98 149.86 0)
			(effects
				(font
					(size 1.27 1.27)
				)
				(justify left bottom)
				(hide yes)
			)
		)
		(property "Public" "False"
			(at 350.52 149.86 0)
			(effects
				(font
					(size 1.27 1.27)
				)
				(justify left bottom)
				(hide yes)
			)
		)
		(pin "2"
		)
		(pin "1"
		)
		(instances
			(project "com-express-7-baseboard"
				(path ""
					(reference "C198")
					(unit 1)
				)
				(path ""
					(reference "C171")
					(unit 1)
				)
			)
		)
	)
	(symbol
		(lib_id "antmicropower:GND")
		(at 276.86 215.9 0)
		(mirror y)
		(unit 1)
		(exclude_from_sim no)
		(in_bom yes)
		(on_board yes)
		(dnp no)
		(fields_autoplaced yes)
		(property "Reference" "#PWR0360"
			(at 276.86 222.25 0)
			(effects
				(font
					(size 1.27 1.27)
				)
				(justify left bottom)
				(hide yes)
			)
		)
		(property "Value" "GND"
			(at 276.86 220.98 0)
			(effects
				(font
					(size 1.27 1.27)
				)
			)
		)
		(property "Footprint" ""
			(at 276.86 215.9 0)
			(effects
				(font
					(size 1.27 1.27)
				)
				(justify left bottom)
				(hide yes)
			)
		)
		(property "Datasheet" ""
			(at 276.86 215.9 0)
			(effects
				(font
					(size 1.27 1.27)
				)
				(justify left bottom)
				(hide yes)
			)
		)
		(property "Description" ""
			(at 276.86 215.9 0)
			(effects
				(font
					(size 1.27 1.27)
				)
				(hide yes)
			)
		)
		(property "Author" "Antmicro"
			(at 267.97 223.52 0)
			(effects
				(font
					(size 1.27 1.27)
					(thickness 0.15)
				)
				(justify left bottom)
				(hide yes)
			)
		)
		(property "License" "Apache-2.0"
			(at 267.97 226.06 0)
			(effects
				(font
					(size 1.27 1.27)
					(thickness 0.15)
				)
				(justify left bottom)
				(hide yes)
			)
		)
		(pin "1"
		)
		(instances
			(project "com-express-7-baseboard"
				(path ""
					(reference "#PWR0411")
					(unit 1)
				)
				(path ""
					(reference "#PWR0360")
					(unit 1)
				)
			)
		)
	)
	(symbol
		(lib_id "antmicroCapacitors0402:C_100n_0402")
		(at 327.66 215.9 90)
		(unit 1)
		(exclude_from_sim no)
		(in_bom yes)
		(on_board yes)
		(dnp no)
		(fields_autoplaced yes)
		(property "Reference" "C174"
			(at 330.2 212.0836 90)
			(effects
				(font
					(size 1.27 1.27)
					(thickness 0.15)
				)
				(justify right)
			)
		)
		(property "Value" "C_100n_0402"
			(at 337.82 195.58 0)
			(effects
				(font
					(size 1.27 1.27)
					(thickness 0.15)
				)
				(justify left bottom)
				(hide yes)
			)
		)
		(property "Footprint" "antmicro-footprints:C_0402_1005Metric"
			(at 340.36 195.58 0)
			(effects
				(font
					(size 1.27 1.27)
					(thickness 0.15)
				)
				(justify left bottom)
				(hide yes)
			)
		)
		(property "Datasheet" "https://www.murata.com/products/productdetail?partno=GRM155R61H104KE14%23"
			(at 342.9 195.58 0)
			(effects
				(font
					(size 1.27 1.27)
					(thickness 0.15)
				)
				(justify left bottom)
				(hide yes)
			)
		)
		(property "Description" ""
			(at 327.66 215.9 0)
			(effects
				(font
					(size 1.27 1.27)
				)
				(hide yes)
			)
		)
		(property "MPN" "GRM155R61H104KE14D"
			(at 345.44 195.58 0)
			(effects
				(font
					(size 1.27 1.27)
					(thickness 0.15)
				)
				(justify left bottom)
				(hide yes)
			)
		)
		(property "Manufacturer" "Murata"
			(at 347.98 195.58 0)
			(effects
				(font
					(size 1.27 1.27)
					(thickness 0.15)
				)
				(justify left bottom)
				(hide yes)
			)
		)
		(property "License" "Apache-2.0"
			(at 350.52 195.58 0)
			(effects
				(font
					(size 1.27 1.27)
					(thickness 0.15)
				)
				(justify left bottom)
				(hide yes)
			)
		)
		(property "Author" "Antmicro"
			(at 353.06 195.58 0)
			(effects
				(font
					(size 1.27 1.27)
					(thickness 0.15)
				)
				(justify left bottom)
				(hide yes)
			)
		)
		(property "Val" "100n"
			(at 330.2 214.6236 90)
			(effects
				(font
					(size 1.27 1.27)
					(thickness 0.15)
				)
				(justify right)
			)
		)
		(property "Voltage" "50V"
			(at 355.6 195.58 0)
			(effects
				(font
					(size 1.27 1.27)
				)
				(justify left bottom)
				(hide yes)
			)
		)
		(property "Dielectric" "X5R"
			(at 358.14 195.58 0)
			(effects
				(font
					(size 1.27 1.27)
				)
				(justify left bottom)
				(hide yes)
			)
		)
		(property "Public" "False"
			(at 360.68 195.58 0)
			(effects
				(font
					(size 1.27 1.27)
				)
				(justify left bottom)
				(hide yes)
			)
		)
		(pin "2"
		)
		(pin "1"
		)
		(instances
			(project "com-express-7-baseboard"
				(path ""
					(reference "C201")
					(unit 1)
				)
				(path ""
					(reference "C174")
					(unit 1)
				)
			)
		)
	)
	(symbol
		(lib_id "antmicroTestPoints:TP_0.75mm_SMD")
		(at 149.86 213.36 0)
		(mirror y)
		(unit 1)
		(exclude_from_sim no)
		(in_bom no)
		(on_board yes)
		(dnp no)
		(fields_autoplaced yes)
		(property "Reference" "TP62"
			(at 144.78 213.36 0)
			(effects
				(font
					(size 1.27 1.27)
					(thickness 0.15)
				)
				(justify left)
			)
		)
		(property "Value" "TP_0.75mm_SMD"
			(at 139.065 217.17 0)
			(effects
				(font
					(size 1.27 1.27)
					(thickness 0.15)
				)
				(justify left bottom)
				(hide yes)
			)
		)
		(property "Footprint" "antmicro-footprints:TP_SMD_0.75mm"
			(at 139.065 219.71 0)
			(effects
				(font
					(size 1.27 1.27)
					(thickness 0.15)
				)
				(justify left bottom)
				(hide yes)
			)
		)
		(property "Datasheet" ""
			(at 132.08 226.06 0)
			(effects
				(font
					(size 1.27 1.27)
					(thickness 0.15)
				)
				(justify left bottom)
				(hide yes)
			)
		)
		(property "Description" ""
			(at 149.86 213.36 0)
			(effects
				(font
					(size 1.27 1.27)
				)
				(hide yes)
			)
		)
		(property "MPN" ""
			(at 139.065 224.79 0)
			(effects
				(font
					(size 1.27 1.27)
					(thickness 0.15)
				)
				(justify left bottom)
				(hide yes)
			)
		)
		(property "Manufacturer" ""
			(at 139.065 219.71 0)
			(effects
				(font
					(size 1.27 1.27)
					(thickness 0.15)
				)
				(justify left bottom)
				(hide yes)
			)
		)
		(property "Author" "Antmicro"
			(at 139.065 222.25 0)
			(effects
				(font
					(size 1.27 1.27)
					(thickness 0.15)
				)
				(justify left bottom)
				(hide yes)
			)
		)
		(property "License" "Apache-2.0"
			(at 139.065 224.79 0)
			(effects
				(font
					(size 1.27 1.27)
					(thickness 0.15)
				)
				(justify left bottom)
				(hide yes)
			)
		)
		(property "Public" "False"
			(at 139.7 227.33 0)
			(effects
				(font
					(size 1.27 1.27)
				)
				(justify left bottom)
				(hide yes)
			)
		)
		(pin "1"
		)
		(instances
			(project "com-express-7-baseboard"
				(path ""
					(reference "TP82")
					(unit 1)
				)
				(path ""
					(reference "TP62")
					(unit 1)
				)
			)
		)
	)
	(symbol
		(lib_id "antmicroCapacitors0402:C_100n_0402")
		(at 287.02 215.9 90)
		(unit 1)
		(exclude_from_sim no)
		(in_bom yes)
		(on_board yes)
		(dnp no)
		(fields_autoplaced yes)
		(property "Reference" "C163"
			(at 289.56 212.0836 90)
			(effects
				(font
					(size 1.27 1.27)
					(thickness 0.15)
				)
				(justify right)
			)
		)
		(property "Value" "C_100n_0402"
			(at 297.18 195.58 0)
			(effects
				(font
					(size 1.27 1.27)
					(thickness 0.15)
				)
				(justify left bottom)
				(hide yes)
			)
		)
		(property "Footprint" "antmicro-footprints:C_0402_1005Metric"
			(at 299.72 195.58 0)
			(effects
				(font
					(size 1.27 1.27)
					(thickness 0.15)
				)
				(justify left bottom)
				(hide yes)
			)
		)
		(property "Datasheet" "https://www.murata.com/products/productdetail?partno=GRM155R61H104KE14%23"
			(at 302.26 195.58 0)
			(effects
				(font
					(size 1.27 1.27)
					(thickness 0.15)
				)
				(justify left bottom)
				(hide yes)
			)
		)
		(property "Description" ""
			(at 287.02 215.9 0)
			(effects
				(font
					(size 1.27 1.27)
				)
				(hide yes)
			)
		)
		(property "MPN" "GRM155R61H104KE14D"
			(at 304.8 195.58 0)
			(effects
				(font
					(size 1.27 1.27)
					(thickness 0.15)
				)
				(justify left bottom)
				(hide yes)
			)
		)
		(property "Manufacturer" "Murata"
			(at 307.34 195.58 0)
			(effects
				(font
					(size 1.27 1.27)
					(thickness 0.15)
				)
				(justify left bottom)
				(hide yes)
			)
		)
		(property "License" "Apache-2.0"
			(at 309.88 195.58 0)
			(effects
				(font
					(size 1.27 1.27)
					(thickness 0.15)
				)
				(justify left bottom)
				(hide yes)
			)
		)
		(property "Author" "Antmicro"
			(at 312.42 195.58 0)
			(effects
				(font
					(size 1.27 1.27)
					(thickness 0.15)
				)
				(justify left bottom)
				(hide yes)
			)
		)
		(property "Val" "100n"
			(at 289.56 214.6236 90)
			(effects
				(font
					(size 1.27 1.27)
					(thickness 0.15)
				)
				(justify right)
			)
		)
		(property "Voltage" "50V"
			(at 314.96 195.58 0)
			(effects
				(font
					(size 1.27 1.27)
				)
				(justify left bottom)
				(hide yes)
			)
		)
		(property "Dielectric" "X5R"
			(at 317.5 195.58 0)
			(effects
				(font
					(size 1.27 1.27)
				)
				(justify left bottom)
				(hide yes)
			)
		)
		(property "Public" "False"
			(at 320.04 195.58 0)
			(effects
				(font
					(size 1.27 1.27)
				)
				(justify left bottom)
				(hide yes)
			)
		)
		(pin "2"
		)
		(pin "1"
		)
		(instances
			(project "com-express-7-baseboard"
				(path ""
					(reference "C190")
					(unit 1)
				)
				(path ""
					(reference "C163")
					(unit 1)
				)
			)
		)
	)
	(symbol
		(lib_id "antmicropower:GND")
		(at 287.02 238.76 0)
		(mirror y)
		(unit 1)
		(exclude_from_sim no)
		(in_bom yes)
		(on_board yes)
		(dnp no)
		(fields_autoplaced yes)
		(property "Reference" "#PWR0366"
			(at 287.02 245.11 0)
			(effects
				(font
					(size 1.27 1.27)
				)
				(justify left bottom)
				(hide yes)
			)
		)
		(property "Value" "GND"
			(at 287.02 243.84 0)
			(effects
				(font
					(size 1.27 1.27)
				)
			)
		)
		(property "Footprint" ""
			(at 287.02 238.76 0)
			(effects
				(font
					(size 1.27 1.27)
				)
				(justify left bottom)
				(hide yes)
			)
		)
		(property "Datasheet" ""
			(at 287.02 238.76 0)
			(effects
				(font
					(size 1.27 1.27)
				)
				(justify left bottom)
				(hide yes)
			)
		)
		(property "Description" ""
			(at 287.02 238.76 0)
			(effects
				(font
					(size 1.27 1.27)
				)
				(hide yes)
			)
		)
		(property "Author" "Antmicro"
			(at 278.13 246.38 0)
			(effects
				(font
					(size 1.27 1.27)
					(thickness 0.15)
				)
				(justify left bottom)
				(hide yes)
			)
		)
		(property "License" "Apache-2.0"
			(at 278.13 248.92 0)
			(effects
				(font
					(size 1.27 1.27)
					(thickness 0.15)
				)
				(justify left bottom)
				(hide yes)
			)
		)
		(pin "1"
		)
		(instances
			(project "com-express-7-baseboard"
				(path ""
					(reference "#PWR0417")
					(unit 1)
				)
				(path ""
					(reference "#PWR0366")
					(unit 1)
				)
			)
		)
	)
	(symbol
		(lib_id "antmicroTestPoints:TP_0.75mm_SMD")
		(at 194.31 200.66 0)
		(unit 1)
		(exclude_from_sim no)
		(in_bom no)
		(on_board yes)
		(dnp no)
		(fields_autoplaced yes)
		(property "Reference" "TP70"
			(at 199.39 200.66 0)
			(effects
				(font
					(size 1.27 1.27)
					(thickness 0.15)
				)
				(justify left)
			)
		)
		(property "Value" "TP_0.75mm_SMD"
			(at 205.105 204.47 0)
			(effects
				(font
					(size 1.27 1.27)
					(thickness 0.15)
				)
				(justify left bottom)
				(hide yes)
			)
		)
		(property "Footprint" "antmicro-footprints:TP_SMD_0.75mm"
			(at 205.105 207.01 0)
			(effects
				(font
					(size 1.27 1.27)
					(thickness 0.15)
				)
				(justify left bottom)
				(hide yes)
			)
		)
		(property "Datasheet" ""
			(at 212.09 213.36 0)
			(effects
				(font
					(size 1.27 1.27)
					(thickness 0.15)
				)
				(justify left bottom)
				(hide yes)
			)
		)
		(property "Description" ""
			(at 194.31 200.66 0)
			(effects
				(font
					(size 1.27 1.27)
				)
				(hide yes)
			)
		)
		(property "MPN" ""
			(at 205.105 212.09 0)
			(effects
				(font
					(size 1.27 1.27)
					(thickness 0.15)
				)
				(justify left bottom)
				(hide yes)
			)
		)
		(property "Manufacturer" ""
			(at 205.105 207.01 0)
			(effects
				(font
					(size 1.27 1.27)
					(thickness 0.15)
				)
				(justify left bottom)
				(hide yes)
			)
		)
		(property "Author" "Antmicro"
			(at 205.105 209.55 0)
			(effects
				(font
					(size 1.27 1.27)
					(thickness 0.15)
				)
				(justify left bottom)
				(hide yes)
			)
		)
		(property "License" "Apache-2.0"
			(at 205.105 212.09 0)
			(effects
				(font
					(size 1.27 1.27)
					(thickness 0.15)
				)
				(justify left bottom)
				(hide yes)
			)
		)
		(property "Public" "False"
			(at 204.47 214.63 0)
			(effects
				(font
					(size 1.27 1.27)
				)
				(justify left bottom)
				(hide yes)
			)
		)
		(pin "1"
		)
		(instances
			(project "com-express-7-baseboard"
				(path ""
					(reference "TP90")
					(unit 1)
				)
				(path ""
					(reference "TP70")
					(unit 1)
				)
			)
		)
	)
	(symbol
		(lib_id "antmicroTestPoints:TP_0.75mm_SMD")
		(at 149.86 210.82 0)
		(mirror y)
		(unit 1)
		(exclude_from_sim no)
		(in_bom no)
		(on_board yes)
		(dnp no)
		(fields_autoplaced yes)
		(property "Reference" "TP61"
			(at 144.78 210.82 0)
			(effects
				(font
					(size 1.27 1.27)
					(thickness 0.15)
				)
				(justify left)
			)
		)
		(property "Value" "TP_0.75mm_SMD"
			(at 139.065 214.63 0)
			(effects
				(font
					(size 1.27 1.27)
					(thickness 0.15)
				)
				(justify left bottom)
				(hide yes)
			)
		)
		(property "Footprint" "antmicro-footprints:TP_SMD_0.75mm"
			(at 139.065 217.17 0)
			(effects
				(font
					(size 1.27 1.27)
					(thickness 0.15)
				)
				(justify left bottom)
				(hide yes)
			)
		)
		(property "Datasheet" ""
			(at 132.08 223.52 0)
			(effects
				(font
					(size 1.27 1.27)
					(thickness 0.15)
				)
				(justify left bottom)
				(hide yes)
			)
		)
		(property "Description" ""
			(at 149.86 210.82 0)
			(effects
				(font
					(size 1.27 1.27)
				)
				(hide yes)
			)
		)
		(property "MPN" ""
			(at 139.065 222.25 0)
			(effects
				(font
					(size 1.27 1.27)
					(thickness 0.15)
				)
				(justify left bottom)
				(hide yes)
			)
		)
		(property "Manufacturer" ""
			(at 139.065 217.17 0)
			(effects
				(font
					(size 1.27 1.27)
					(thickness 0.15)
				)
				(justify left bottom)
				(hide yes)
			)
		)
		(property "Author" "Antmicro"
			(at 139.065 219.71 0)
			(effects
				(font
					(size 1.27 1.27)
					(thickness 0.15)
				)
				(justify left bottom)
				(hide yes)
			)
		)
		(property "License" "Apache-2.0"
			(at 139.065 222.25 0)
			(effects
				(font
					(size 1.27 1.27)
					(thickness 0.15)
				)
				(justify left bottom)
				(hide yes)
			)
		)
		(property "Public" "False"
			(at 139.7 224.79 0)
			(effects
				(font
					(size 1.27 1.27)
				)
				(justify left bottom)
				(hide yes)
			)
		)
		(pin "1"
		)
		(instances
			(project "com-express-7-baseboard"
				(path ""
					(reference "TP81")
					(unit 1)
				)
				(path ""
					(reference "TP61")
					(unit 1)
				)
			)
		)
	)
	(symbol
		(lib_id "antmicropower:GND")
		(at 287.02 193.04 0)
		(mirror y)
		(unit 1)
		(exclude_from_sim no)
		(in_bom yes)
		(on_board yes)
		(dnp no)
		(fields_autoplaced yes)
		(property "Reference" "#PWR0364"
			(at 287.02 199.39 0)
			(effects
				(font
					(size 1.27 1.27)
				)
				(justify left bottom)
				(hide yes)
			)
		)
		(property "Value" "GND"
			(at 287.02 198.12 0)
			(effects
				(font
					(size 1.27 1.27)
				)
			)
		)
		(property "Footprint" ""
			(at 287.02 193.04 0)
			(effects
				(font
					(size 1.27 1.27)
				)
				(justify left bottom)
				(hide yes)
			)
		)
		(property "Datasheet" ""
			(at 287.02 193.04 0)
			(effects
				(font
					(size 1.27 1.27)
				)
				(justify left bottom)
				(hide yes)
			)
		)
		(property "Description" ""
			(at 287.02 193.04 0)
			(effects
				(font
					(size 1.27 1.27)
				)
				(hide yes)
			)
		)
		(property "Author" "Antmicro"
			(at 278.13 200.66 0)
			(effects
				(font
					(size 1.27 1.27)
					(thickness 0.15)
				)
				(justify left bottom)
				(hide yes)
			)
		)
		(property "License" "Apache-2.0"
			(at 278.13 203.2 0)
			(effects
				(font
					(size 1.27 1.27)
					(thickness 0.15)
				)
				(justify left bottom)
				(hide yes)
			)
		)
		(pin "1"
		)
		(instances
			(project "com-express-7-baseboard"
				(path ""
					(reference "#PWR0415")
					(unit 1)
				)
				(path ""
					(reference "#PWR0364")
					(unit 1)
				)
			)
		)
	)
	(symbol
		(lib_id "antmicroInterfaceControllers:TLK10232CTR")
		(at 232.41 71.12 0)
		(unit 2)
		(exclude_from_sim no)
		(in_bom yes)
		(on_board yes)
		(dnp no)
		(fields_autoplaced yes)
		(property "Reference" "U43"
			(at 247.65 63.5 0)
			(effects
				(font
					(size 1.27 1.27)
					(thickness 0.15)
				)
			)
		)
		(property "Value" "TLK10232CTR"
			(at 279.4 81.28 0)
			(effects
				(font
					(size 1.27 1.27)
					(thickness 0.15)
				)
				(justify left bottom)
				(hide yes)
			)
		)
		(property "Footprint" "antmicro-footprints:BGA-144_12x12_13.05x13.05mm_P1.0mm"
			(at 279.4 83.82 0)
			(effects
				(font
					(size 1.27 1.27)
					(thickness 0.15)
				)
				(justify left bottom)
				(hide yes)
			)
		)
		(property "Datasheet" "https://www.ti.com/lit/ds/symlink/tlk10232.pdf?ts=1712150848075&ref_url=https%253A%252F%252Fwww.mouser.pl%252F"
			(at 279.4 86.36 0)
			(effects
				(font
					(size 1.27 1.27)
					(thickness 0.15)
				)
				(justify left bottom)
				(hide yes)
			)
		)
		(property "Description" ""
			(at 232.41 71.12 0)
			(effects
				(font
					(size 1.27 1.27)
				)
				(hide yes)
			)
		)
		(property "MPN" "TLK10232CTR"
			(at 247.65 66.04 0)
			(effects
				(font
					(size 1.27 1.27)
					(thickness 0.15)
				)
			)
		)
		(property "Manufacturer" "Texas Instruments"
			(at 279.4 76.2 0)
			(effects
				(font
					(size 1.27 1.27)
					(thickness 0.15)
				)
				(justify left bottom)
				(hide yes)
			)
		)
		(property "Author" "Antmicro"
			(at 279.4 88.9 0)
			(effects
				(font
					(size 1.27 1.27)
					(thickness 0.15)
				)
				(justify left bottom)
				(hide yes)
			)
		)
		(property "License" "Apache-2.0"
			(at 279.4 91.44 0)
			(effects
				(font
					(size 1.27 1.27)
					(thickness 0.15)
				)
				(justify left bottom)
				(hide yes)
			)
		)
		(pin "J2"
		)
		(pin "A10"
		)
		(pin "E6"
		)
		(pin "A9"
		)
		(pin "F2"
		)
		(pin "B2"
		)
		(pin "J6"
		)
		(pin "J8"
		)
		(pin "E2"
		)
		(pin "J12"
		)
		(pin "G4"
		)
		(pin "A12"
		)
		(pin "K3"
		)
		(pin "F3"
		)
		(pin "C11"
		)
		(pin "M12"
		)
		(pin "F9"
		)
		(pin "B12"
		)
		(pin "K12"
		)
		(pin "C4"
		)
		(pin "B1"
		)
		(pin "D5"
		)
		(pin "D4"
		)
		(pin "F11"
		)
		(pin "B6"
		)
		(pin "E1"
		)
		(pin "E12"
		)
		(pin "K5"
		)
		(pin "M10"
		)
		(pin "L11"
		)
		(pin "H9"
		)
		(pin "E3"
		)
		(pin "B7"
		)
		(pin "D7"
		)
		(pin "A5"
		)
		(pin "K10"
		)
		(pin "G7"
		)
		(pin "L8"
		)
		(pin "G9"
		)
		(pin "G5"
		)
		(pin "E5"
		)
		(pin "M3"
		)
		(pin "M1"
		)
		(pin "A2"
		)
		(pin "E10"
		)
		(pin "D8"
		)
		(pin "B11"
		)
		(pin "J1"
		)
		(pin "D6"
		)
		(pin "M6"
		)
		(pin "J3"
		)
		(pin "M2"
		)
		(pin "L10"
		)
		(pin "F10"
		)
		(pin "D10"
		)
		(pin "E4"
		)
		(pin "F4"
		)
		(pin "E11"
		)
		(pin "A11"
		)
		(pin "H12"
		)
		(pin "G1"
		)
		(pin "H1"
		)
		(pin "K7"
		)
		(pin "G8"
		)
		(pin "H4"
		)
		(pin "K2"
		)
		(pin "L3"
		)
		(pin "F6"
		)
		(pin "H6"
		)
		(pin "G10"
		)
		(pin "H11"
		)
		(pin "J4"
		)
		(pin "K4"
		)
		(pin "H3"
		)
		(pin "J10"
		)
		(pin "F12"
		)
		(pin "H5"
		)
		(pin "M4"
		)
		(pin "B3"
		)
		(pin "B4"
		)
		(pin "M9"
		)
		(pin "K6"
		)
		(pin "M8"
		)
		(pin "D3"
		)
		(pin "H10"
		)
		(pin "F8"
		)
		(pin "K8"
		)
		(pin "F7"
		)
		(pin "C5"
		)
		(pin "L1"
		)
		(pin "E9"
		)
		(pin "L2"
		)
		(pin "L5"
		)
		(pin "L6"
		)
		(pin "B8"
		)
		(pin "L12"
		)
		(pin "C9"
		)
		(pin "F5"
		)
		(pin "D2"
		)
		(pin "D11"
		)
		(pin "D1"
		)
		(pin "C8"
		)
		(pin "H2"
		)
		(pin "M11"
		)
		(pin "D12"
		)
		(pin "D9"
		)
		(pin "A1"
		)
		(pin "G12"
		)
		(pin "C2"
		)
		(pin "A8"
		)
		(pin "B10"
		)
		(pin "A7"
		)
		(pin "C10"
		)
		(pin "A4"
		)
		(pin "A3"
		)
		(pin "B5"
		)
		(pin "L4"
		)
		(pin "B9"
		)
		(pin "J5"
		)
		(pin "M5"
		)
		(pin "G2"
		)
		(pin "J11"
		)
		(pin "A6"
		)
		(pin "K9"
		)
		(pin "C3"
		)
		(pin "G6"
		)
		(pin "L7"
		)
		(pin "L9"
		)
		(pin "C12"
		)
		(pin "C1"
		)
		(pin "E7"
		)
		(pin "H7"
		)
		(pin "M7"
		)
		(pin "C7"
		)
		(pin "F1"
		)
		(pin "J7"
		)
		(pin "G3"
		)
		(pin "J9"
		)
		(pin "K11"
		)
		(pin "E8"
		)
		(pin "H8"
		)
		(pin "K1"
		)
		(pin "C6"
		)
		(pin "G11"
		)
		(instances
			(project "com-express-7-baseboard"
				(path ""
					(reference "U45")
					(unit 2)
				)
				(path ""
					(reference "U43")
					(unit 2)
				)
			)
		)
	)
	(symbol
		(lib_id "antmicroResistorsmisc:R_0R_0201")
		(at 107.95 71.12 90)
		(unit 1)
		(exclude_from_sim no)
		(in_bom yes)
		(on_board yes)
		(dnp yes)
		(property "Reference" "R249"
			(at 106.68 63.5 0)
			(effects
				(font
					(size 1.27 1.27)
					(thickness 0.15)
				)
			)
		)
		(property "Value" "R_0R_0201"
			(at 120.65 50.8 0)
			(effects
				(font
					(size 1.27 1.27)
					(thickness 0.15)
				)
				(justify left bottom)
				(hide yes)
			)
		)
		(property "Footprint" "antmicro-footprints:R_0201"
			(at 123.19 50.8 0)
			(effects
				(font
					(size 1.27 1.27)
					(thickness 0.15)
				)
				(justify left bottom)
				(hide yes)
			)
		)
		(property "Datasheet" "https://www.bourns.com/docs/product-datasheets/cr.pdf"
			(at 125.73 50.8 0)
			(effects
				(font
					(size 1.27 1.27)
					(thickness 0.15)
				)
				(justify left bottom)
				(hide yes)
			)
		)
		(property "Description" ""
			(at 107.95 71.12 0)
			(effects
				(font
					(size 1.27 1.27)
				)
				(hide yes)
			)
		)
		(property "MPN" "CR0201-FX-0R00GLF"
			(at 128.27 50.8 0)
			(effects
				(font
					(size 1.27 1.27)
					(thickness 0.15)
				)
				(justify left bottom)
				(hide yes)
			)
		)
		(property "Manufacturer" "Bourns"
			(at 130.81 50.8 0)
			(effects
				(font
					(size 1.27 1.27)
					(thickness 0.15)
				)
				(justify left bottom)
				(hide yes)
			)
		)
		(property "License" "Apache-2.0"
			(at 133.35 50.8 0)
			(effects
				(font
					(size 1.27 1.27)
					(thickness 0.15)
				)
				(justify left bottom)
				(hide yes)
			)
		)
		(property "Author" "Antmicro"
			(at 135.89 50.8 0)
			(effects
				(font
					(size 1.27 1.27)
					(thickness 0.15)
				)
				(justify left bottom)
				(hide yes)
			)
		)
		(property "Val" "0R"
			(at 106.68 72.39 0)
			(effects
				(font
					(size 1.27 1.27)
					(thickness 0.15)
				)
			)
		)
		(property "Tolerance" "1%"
			(at 118.11 50.8 0)
			(effects
				(font
					(size 1.27 1.27)
				)
				(justify left bottom)
				(hide yes)
			)
		)
		(pin "1"
		)
		(pin "2"
		)
		(instances
			(project "com-express-7-baseboard"
				(path ""
					(reference "R283")
					(unit 1)
				)
				(path ""
					(reference "R249")
					(unit 1)
				)
			)
		)
	)
	(symbol
		(lib_id "antmicroInterfaceControllers:TLK10232CTR")
		(at 160.02 185.42 0)
		(unit 3)
		(exclude_from_sim no)
		(in_bom yes)
		(on_board yes)
		(dnp no)
		(fields_autoplaced yes)
		(property "Reference" "U43"
			(at 175.26 177.8 0)
			(effects
				(font
					(size 1.27 1.27)
					(thickness 0.15)
				)
			)
		)
		(property "Value" "TLK10232CTR"
			(at 207.01 195.58 0)
			(effects
				(font
					(size 1.27 1.27)
					(thickness 0.15)
				)
				(justify left bottom)
				(hide yes)
			)
		)
		(property "Footprint" "antmicro-footprints:BGA-144_12x12_13.05x13.05mm_P1.0mm"
			(at 207.01 198.12 0)
			(effects
				(font
					(size 1.27 1.27)
					(thickness 0.15)
				)
				(justify left bottom)
				(hide yes)
			)
		)
		(property "Datasheet" "https://www.ti.com/lit/ds/symlink/tlk10232.pdf?ts=1712150848075&ref_url=https%253A%252F%252Fwww.mouser.pl%252F"
			(at 207.01 200.66 0)
			(effects
				(font
					(size 1.27 1.27)
					(thickness 0.15)
				)
				(justify left bottom)
				(hide yes)
			)
		)
		(property "Description" ""
			(at 160.02 185.42 0)
			(effects
				(font
					(size 1.27 1.27)
				)
				(hide yes)
			)
		)
		(property "MPN" "TLK10232CTR"
			(at 175.26 180.34 0)
			(effects
				(font
					(size 1.27 1.27)
					(thickness 0.15)
				)
			)
		)
		(property "Manufacturer" "Texas Instruments"
			(at 207.01 190.5 0)
			(effects
				(font
					(size 1.27 1.27)
					(thickness 0.15)
				)
				(justify left bottom)
				(hide yes)
			)
		)
		(property "Author" "Antmicro"
			(at 207.01 203.2 0)
			(effects
				(font
					(size 1.27 1.27)
					(thickness 0.15)
				)
				(justify left bottom)
				(hide yes)
			)
		)
		(property "License" "Apache-2.0"
			(at 207.01 205.74 0)
			(effects
				(font
					(size 1.27 1.27)
					(thickness 0.15)
				)
				(justify left bottom)
				(hide yes)
			)
		)
		(pin "G11"
		)
		(pin "K5"
		)
		(pin "C11"
		)
		(pin "H6"
		)
		(pin "M11"
		)
		(pin "F6"
		)
		(pin "B5"
		)
		(pin "B2"
		)
		(pin "B1"
		)
		(pin "M10"
		)
		(pin "M8"
		)
		(pin "A3"
		)
		(pin "A1"
		)
		(pin "A12"
		)
		(pin "A11"
		)
		(pin "G1"
		)
		(pin "B12"
		)
		(pin "F7"
		)
		(pin "M9"
		)
		(pin "E1"
		)
		(pin "D9"
		)
		(pin "A7"
		)
		(pin "K10"
		)
		(pin "B10"
		)
		(pin "A2"
		)
		(pin "H3"
		)
		(pin "F8"
		)
		(pin "F9"
		)
		(pin "G7"
		)
		(pin "F4"
		)
		(pin "H1"
		)
		(pin "H12"
		)
		(pin "F5"
		)
		(pin "D12"
		)
		(pin "B6"
		)
		(pin "A6"
		)
		(pin "F2"
		)
		(pin "A4"
		)
		(pin "D1"
		)
		(pin "A8"
		)
		(pin "C5"
		)
		(pin "C2"
		)
		(pin "E6"
		)
		(pin "F1"
		)
		(pin "H8"
		)
		(pin "K8"
		)
		(pin "B8"
		)
		(pin "C10"
		)
		(pin "M3"
		)
		(pin "M6"
		)
		(pin "E10"
		)
		(pin "E11"
		)
		(pin "B11"
		)
		(pin "M7"
		)
		(pin "D5"
		)
		(pin "E5"
		)
		(pin "H10"
		)
		(pin "E7"
		)
		(pin "L2"
		)
		(pin "C6"
		)
		(pin "B7"
		)
		(pin "L12"
		)
		(pin "K2"
		)
		(pin "G9"
		)
		(pin "K1"
		)
		(pin "A5"
		)
		(pin "L7"
		)
		(pin "E2"
		)
		(pin "K3"
		)
		(pin "C12"
		)
		(pin "D6"
		)
		(pin "J11"
		)
		(pin "J9"
		)
		(pin "J7"
		)
		(pin "H4"
		)
		(pin "D10"
		)
		(pin "J10"
		)
		(pin "K4"
		)
		(pin "G5"
		)
		(pin "F11"
		)
		(pin "G3"
		)
		(pin "G8"
		)
		(pin "C8"
		)
		(pin "M4"
		)
		(pin "C9"
		)
		(pin "G6"
		)
		(pin "F10"
		)
		(pin "H11"
		)
		(pin "J8"
		)
		(pin "M5"
		)
		(pin "C7"
		)
		(pin "H2"
		)
		(pin "B3"
		)
		(pin "M1"
		)
		(pin "C3"
		)
		(pin "D8"
		)
		(pin "K7"
		)
		(pin "E4"
		)
		(pin "L11"
		)
		(pin "D3"
		)
		(pin "H9"
		)
		(pin "F3"
		)
		(pin "B9"
		)
		(pin "D4"
		)
		(pin "C4"
		)
		(pin "L5"
		)
		(pin "E9"
		)
		(pin "K11"
		)
		(pin "E12"
		)
		(pin "G4"
		)
		(pin "J12"
		)
		(pin "E8"
		)
		(pin "J5"
		)
		(pin "J2"
		)
		(pin "G12"
		)
		(pin "G2"
		)
		(pin "M2"
		)
		(pin "D11"
		)
		(pin "J4"
		)
		(pin "K12"
		)
		(pin "K9"
		)
		(pin "L4"
		)
		(pin "L8"
		)
		(pin "L3"
		)
		(pin "E3"
		)
		(pin "F12"
		)
		(pin "M12"
		)
		(pin "A10"
		)
		(pin "L6"
		)
		(pin "D2"
		)
		(pin "H7"
		)
		(pin "J6"
		)
		(pin "C1"
		)
		(pin "J3"
		)
		(pin "A9"
		)
		(pin "K6"
		)
		(pin "G10"
		)
		(pin "B4"
		)
		(pin "D7"
		)
		(pin "L1"
		)
		(pin "H5"
		)
		(pin "J1"
		)
		(pin "L10"
		)
		(pin "L9"
		)
		(instances
			(project "com-express-7-baseboard"
				(path ""
					(reference "U45")
					(unit 3)
				)
				(path ""
					(reference "U43")
					(unit 3)
				)
			)
		)
	)
	(symbol
		(lib_id "antmicroTestPoints:TP_0.75mm_SMD")
		(at 157.48 243.84 0)
		(mirror y)
		(unit 1)
		(exclude_from_sim no)
		(in_bom no)
		(on_board yes)
		(dnp no)
		(fields_autoplaced yes)
		(property "Reference" "TP66"
			(at 152.4 243.84 0)
			(effects
				(font
					(size 1.27 1.27)
					(thickness 0.15)
				)
				(justify left)
			)
		)
		(property "Value" "TP_0.75mm_SMD"
			(at 146.685 247.65 0)
			(effects
				(font
					(size 1.27 1.27)
					(thickness 0.15)
				)
				(justify left bottom)
				(hide yes)
			)
		)
		(property "Footprint" "antmicro-footprints:TP_SMD_0.75mm"
			(at 146.685 250.19 0)
			(effects
				(font
					(size 1.27 1.27)
					(thickness 0.15)
				)
				(justify left bottom)
				(hide yes)
			)
		)
		(property "Datasheet" ""
			(at 139.7 256.54 0)
			(effects
				(font
					(size 1.27 1.27)
					(thickness 0.15)
				)
				(justify left bottom)
				(hide yes)
			)
		)
		(property "Description" ""
			(at 157.48 243.84 0)
			(effects
				(font
					(size 1.27 1.27)
				)
				(hide yes)
			)
		)
		(property "MPN" ""
			(at 146.685 255.27 0)
			(effects
				(font
					(size 1.27 1.27)
					(thickness 0.15)
				)
				(justify left bottom)
				(hide yes)
			)
		)
		(property "Manufacturer" ""
			(at 146.685 250.19 0)
			(effects
				(font
					(size 1.27 1.27)
					(thickness 0.15)
				)
				(justify left bottom)
				(hide yes)
			)
		)
		(property "Author" "Antmicro"
			(at 146.685 252.73 0)
			(effects
				(font
					(size 1.27 1.27)
					(thickness 0.15)
				)
				(justify left bottom)
				(hide yes)
			)
		)
		(property "License" "Apache-2.0"
			(at 146.685 255.27 0)
			(effects
				(font
					(size 1.27 1.27)
					(thickness 0.15)
				)
				(justify left bottom)
				(hide yes)
			)
		)
		(property "Public" "False"
			(at 147.32 257.81 0)
			(effects
				(font
					(size 1.27 1.27)
				)
				(justify left bottom)
				(hide yes)
			)
		)
		(pin "1"
		)
		(instances
			(project "com-express-7-baseboard"
				(path ""
					(reference "TP86")
					(unit 1)
				)
				(path ""
					(reference "TP66")
					(unit 1)
				)
			)
		)
	)
	(symbol
		(lib_id "antmicropower:+1V8")
		(at 261.62 203.2 0)
		(unit 1)
		(exclude_from_sim no)
		(in_bom yes)
		(on_board yes)
		(dnp no)
		(property "Reference" "#PWR0353"
			(at 276.86 205.74 0)
			(effects
				(font
					(size 1.27 1.27)
					(thickness 0.15)
				)
				(justify left bottom)
				(hide yes)
			)
		)
		(property "Value" "+1V8"
			(at 261.62 199.39 0)
			(effects
				(font
					(size 1.27 1.27)
					(thickness 0.15)
				)
			)
		)
		(property "Footprint" ""
			(at 276.86 210.82 0)
			(effects
				(font
					(size 1.27 1.27)
					(thickness 0.15)
				)
				(justify left bottom)
				(hide yes)
			)
		)
		(property "Datasheet" ""
			(at 276.86 213.36 0)
			(effects
				(font
					(size 1.27 1.27)
					(thickness 0.15)
				)
				(justify left bottom)
				(hide yes)
			)
		)
		(property "Description" ""
			(at 261.62 203.2 0)
			(effects
				(font
					(size 1.27 1.27)
				)
				(hide yes)
			)
		)
		(property "Author" "Antmicro"
			(at 276.86 208.28 0)
			(effects
				(font
					(size 1.27 1.27)
					(thickness 0.15)
				)
				(justify left bottom)
				(hide yes)
			)
		)
		(property "License" "Apache-2.0"
			(at 276.86 210.82 0)
			(effects
				(font
					(size 1.27 1.27)
					(thickness 0.15)
				)
				(justify left bottom)
				(hide yes)
			)
		)
		(pin "1"
		)
		(instances
			(project "com-express-7-baseboard"
				(path ""
					(reference "#PWR0404")
					(unit 1)
				)
				(path ""
					(reference "#PWR0353")
					(unit 1)
				)
			)
		)
	)
	(symbol
		(lib_id "antmicropower:GND")
		(at 193.04 250.19 0)
		(mirror y)
		(unit 1)
		(exclude_from_sim no)
		(in_bom yes)
		(on_board yes)
		(dnp no)
		(fields_autoplaced yes)
		(property "Reference" "#PWR0341"
			(at 193.04 256.54 0)
			(effects
				(font
					(size 1.27 1.27)
				)
				(justify left bottom)
				(hide yes)
			)
		)
		(property "Value" "GND"
			(at 193.04 255.27 0)
			(effects
				(font
					(size 1.27 1.27)
				)
			)
		)
		(property "Footprint" ""
			(at 193.04 250.19 0)
			(effects
				(font
					(size 1.27 1.27)
				)
				(justify left bottom)
				(hide yes)
			)
		)
		(property "Datasheet" ""
			(at 193.04 250.19 0)
			(effects
				(font
					(size 1.27 1.27)
				)
				(justify left bottom)
				(hide yes)
			)
		)
		(property "Description" ""
			(at 193.04 250.19 0)
			(effects
				(font
					(size 1.27 1.27)
				)
				(hide yes)
			)
		)
		(property "Author" "Antmicro"
			(at 184.15 257.81 0)
			(effects
				(font
					(size 1.27 1.27)
					(thickness 0.15)
				)
				(justify left bottom)
				(hide yes)
			)
		)
		(property "License" "Apache-2.0"
			(at 184.15 260.35 0)
			(effects
				(font
					(size 1.27 1.27)
					(thickness 0.15)
				)
				(justify left bottom)
				(hide yes)
			)
		)
		(pin "1"
		)
		(instances
			(project "com-express-7-baseboard"
				(path ""
					(reference "#PWR0392")
					(unit 1)
				)
				(path ""
					(reference "#PWR0341")
					(unit 1)
				)
			)
		)
	)
	(symbol
		(lib_id "antmicroResistorsmisc:R_0R_0201")
		(at 312.42 71.12 90)
		(unit 1)
		(exclude_from_sim no)
		(in_bom yes)
		(on_board yes)
		(dnp yes)
		(property "Reference" "R278"
			(at 311.15 63.5 0)
			(effects
				(font
					(size 1.27 1.27)
					(thickness 0.15)
				)
			)
		)
		(property "Value" "R_0R_0201"
			(at 325.12 50.8 0)
			(effects
				(font
					(size 1.27 1.27)
					(thickness 0.15)
				)
				(justify left bottom)
				(hide yes)
			)
		)
		(property "Footprint" "antmicro-footprints:R_0201"
			(at 327.66 50.8 0)
			(effects
				(font
					(size 1.27 1.27)
					(thickness 0.15)
				)
				(justify left bottom)
				(hide yes)
			)
		)
		(property "Datasheet" "https://www.bourns.com/docs/product-datasheets/cr.pdf"
			(at 330.2 50.8 0)
			(effects
				(font
					(size 1.27 1.27)
					(thickness 0.15)
				)
				(justify left bottom)
				(hide yes)
			)
		)
		(property "Description" ""
			(at 312.42 71.12 0)
			(effects
				(font
					(size 1.27 1.27)
				)
				(hide yes)
			)
		)
		(property "MPN" "CR0201-FX-0R00GLF"
			(at 332.74 50.8 0)
			(effects
				(font
					(size 1.27 1.27)
					(thickness 0.15)
				)
				(justify left bottom)
				(hide yes)
			)
		)
		(property "Manufacturer" "Bourns"
			(at 335.28 50.8 0)
			(effects
				(font
					(size 1.27 1.27)
					(thickness 0.15)
				)
				(justify left bottom)
				(hide yes)
			)
		)
		(property "License" "Apache-2.0"
			(at 337.82 50.8 0)
			(effects
				(font
					(size 1.27 1.27)
					(thickness 0.15)
				)
				(justify left bottom)
				(hide yes)
			)
		)
		(property "Author" "Antmicro"
			(at 340.36 50.8 0)
			(effects
				(font
					(size 1.27 1.27)
					(thickness 0.15)
				)
				(justify left bottom)
				(hide yes)
			)
		)
		(property "Val" "0R"
			(at 311.15 72.39 0)
			(effects
				(font
					(size 1.27 1.27)
					(thickness 0.15)
				)
			)
		)
		(property "Tolerance" "1%"
			(at 322.58 50.8 0)
			(effects
				(font
					(size 1.27 1.27)
				)
				(justify left bottom)
				(hide yes)
			)
		)
		(pin "1"
		)
		(pin "2"
		)
		(instances
			(project "com-express-7-baseboard"
				(path ""
					(reference "R312")
					(unit 1)
				)
				(path ""
					(reference "R278")
					(unit 1)
				)
			)
		)
	)
	(symbol
		(lib_id "antmicroResistors0402:R_10k_0402")
		(at 140.97 248.92 90)
		(unit 1)
		(exclude_from_sim no)
		(in_bom yes)
		(on_board yes)
		(dnp no)
		(property "Reference" "R258"
			(at 142.24 245.11 90)
			(effects
				(font
					(size 1.27 1.27)
					(thickness 0.15)
				)
				(justify right)
			)
		)
		(property "Value" "R_10k_0402"
			(at 153.67 228.6 0)
			(effects
				(font
					(size 1.27 1.27)
					(thickness 0.15)
				)
				(justify left bottom)
				(hide yes)
			)
		)
		(property "Footprint" "antmicro-footprints:R_0402_1005Metric"
			(at 156.21 228.6 0)
			(effects
				(font
					(size 1.27 1.27)
					(thickness 0.15)
				)
				(justify left bottom)
				(hide yes)
			)
		)
		(property "Datasheet" "https://www.bourns.com/docs/product-datasheets/cr.pdf"
			(at 158.75 228.6 0)
			(effects
				(font
					(size 1.27 1.27)
					(thickness 0.15)
				)
				(justify left bottom)
				(hide yes)
			)
		)
		(property "Description" ""
			(at 140.97 248.92 0)
			(effects
				(font
					(size 1.27 1.27)
				)
				(hide yes)
			)
		)
		(property "MPN" "CR0402-FX-1002GLF"
			(at 161.29 228.6 0)
			(effects
				(font
					(size 1.27 1.27)
					(thickness 0.15)
				)
				(justify left bottom)
				(hide yes)
			)
		)
		(property "Manufacturer" "Bourns"
			(at 163.83 228.6 0)
			(effects
				(font
					(size 1.27 1.27)
					(thickness 0.15)
				)
				(justify left bottom)
				(hide yes)
			)
		)
		(property "License" "Apache-2.0"
			(at 166.37 228.6 0)
			(effects
				(font
					(size 1.27 1.27)
					(thickness 0.15)
				)
				(justify left bottom)
				(hide yes)
			)
		)
		(property "Author" "Antmicro"
			(at 168.91 228.6 0)
			(effects
				(font
					(size 1.27 1.27)
					(thickness 0.15)
				)
				(justify left bottom)
				(hide yes)
			)
		)
		(property "Val" "10k"
			(at 142.24 247.65 90)
			(effects
				(font
					(size 1.27 1.27)
					(thickness 0.15)
				)
				(justify right)
			)
		)
		(property "Tolerance" "1%"
			(at 151.13 228.6 0)
			(effects
				(font
					(size 1.27 1.27)
				)
				(justify left bottom)
				(hide yes)
			)
		)
		(property "Public" "False"
			(at 171.45 228.6 0)
			(effects
				(font
					(size 1.27 1.27)
				)
				(justify left bottom)
				(hide yes)
			)
		)
		(pin "2"
		)
		(pin "1"
		)
		(instances
			(project "com-express-7-baseboard"
				(path ""
					(reference "R292")
					(unit 1)
				)
				(path ""
					(reference "R258")
					(unit 1)
				)
			)
		)
	)
	(symbol
		(lib_id "antmicroInterfaceControllers:TLK10232CTR")
		(at 345.44 185.42 0)
		(unit 4)
		(exclude_from_sim no)
		(in_bom yes)
		(on_board yes)
		(dnp no)
		(fields_autoplaced yes)
		(property "Reference" "U43"
			(at 360.68 177.8 0)
			(effects
				(font
					(size 1.27 1.27)
					(thickness 0.15)
				)
			)
		)
		(property "Value" "TLK10232CTR"
			(at 392.43 195.58 0)
			(effects
				(font
					(size 1.27 1.27)
					(thickness 0.15)
				)
				(justify left bottom)
				(hide yes)
			)
		)
		(property "Footprint" "antmicro-footprints:BGA-144_12x12_13.05x13.05mm_P1.0mm"
			(at 392.43 198.12 0)
			(effects
				(font
					(size 1.27 1.27)
					(thickness 0.15)
				)
				(justify left bottom)
				(hide yes)
			)
		)
		(property "Datasheet" "https://www.ti.com/lit/ds/symlink/tlk10232.pdf?ts=1712150848075&ref_url=https%253A%252F%252Fwww.mouser.pl%252F"
			(at 392.43 200.66 0)
			(effects
				(font
					(size 1.27 1.27)
					(thickness 0.15)
				)
				(justify left bottom)
				(hide yes)
			)
		)
		(property "Description" ""
			(at 345.44 185.42 0)
			(effects
				(font
					(size 1.27 1.27)
				)
				(hide yes)
			)
		)
		(property "MPN" "TLK10232CTR"
			(at 360.68 180.34 0)
			(effects
				(font
					(size 1.27 1.27)
					(thickness 0.15)
				)
			)
		)
		(property "Manufacturer" "Texas Instruments"
			(at 392.43 190.5 0)
			(effects
				(font
					(size 1.27 1.27)
					(thickness 0.15)
				)
				(justify left bottom)
				(hide yes)
			)
		)
		(property "Author" "Antmicro"
			(at 392.43 203.2 0)
			(effects
				(font
					(size 1.27 1.27)
					(thickness 0.15)
				)
				(justify left bottom)
				(hide yes)
			)
		)
		(property "License" "Apache-2.0"
			(at 392.43 205.74 0)
			(effects
				(font
					(size 1.27 1.27)
					(thickness 0.15)
				)
				(justify left bottom)
				(hide yes)
			)
		)
		(pin "G11"
		)
		(pin "K5"
		)
		(pin "C11"
		)
		(pin "H6"
		)
		(pin "M11"
		)
		(pin "F6"
		)
		(pin "B5"
		)
		(pin "B2"
		)
		(pin "B1"
		)
		(pin "M10"
		)
		(pin "M8"
		)
		(pin "A3"
		)
		(pin "A1"
		)
		(pin "A12"
		)
		(pin "A11"
		)
		(pin "G1"
		)
		(pin "B12"
		)
		(pin "F7"
		)
		(pin "M9"
		)
		(pin "E1"
		)
		(pin "D9"
		)
		(pin "A7"
		)
		(pin "K10"
		)
		(pin "B10"
		)
		(pin "A2"
		)
		(pin "H3"
		)
		(pin "F8"
		)
		(pin "F9"
		)
		(pin "G7"
		)
		(pin "F4"
		)
		(pin "H1"
		)
		(pin "H12"
		)
		(pin "F5"
		)
		(pin "D12"
		)
		(pin "B6"
		)
		(pin "A6"
		)
		(pin "F2"
		)
		(pin "A4"
		)
		(pin "D1"
		)
		(pin "A8"
		)
		(pin "C5"
		)
		(pin "C2"
		)
		(pin "E6"
		)
		(pin "F1"
		)
		(pin "H8"
		)
		(pin "K8"
		)
		(pin "B8"
		)
		(pin "C10"
		)
		(pin "M3"
		)
		(pin "M6"
		)
		(pin "E10"
		)
		(pin "E11"
		)
		(pin "B11"
		)
		(pin "M7"
		)
		(pin "D5"
		)
		(pin "E5"
		)
		(pin "H10"
		)
		(pin "E7"
		)
		(pin "L2"
		)
		(pin "C6"
		)
		(pin "B7"
		)
		(pin "L12"
		)
		(pin "K2"
		)
		(pin "G9"
		)
		(pin "K1"
		)
		(pin "A5"
		)
		(pin "L7"
		)
		(pin "E2"
		)
		(pin "K3"
		)
		(pin "C12"
		)
		(pin "D6"
		)
		(pin "J11"
		)
		(pin "J9"
		)
		(pin "J7"
		)
		(pin "H4"
		)
		(pin "D10"
		)
		(pin "J10"
		)
		(pin "K4"
		)
		(pin "G5"
		)
		(pin "F11"
		)
		(pin "G3"
		)
		(pin "G8"
		)
		(pin "C8"
		)
		(pin "M4"
		)
		(pin "C9"
		)
		(pin "G6"
		)
		(pin "F10"
		)
		(pin "H11"
		)
		(pin "J8"
		)
		(pin "M5"
		)
		(pin "C7"
		)
		(pin "H2"
		)
		(pin "B3"
		)
		(pin "M1"
		)
		(pin "C3"
		)
		(pin "D8"
		)
		(pin "K7"
		)
		(pin "E4"
		)
		(pin "L11"
		)
		(pin "D3"
		)
		(pin "H9"
		)
		(pin "F3"
		)
		(pin "B9"
		)
		(pin "D4"
		)
		(pin "C4"
		)
		(pin "L5"
		)
		(pin "E9"
		)
		(pin "K11"
		)
		(pin "E12"
		)
		(pin "G4"
		)
		(pin "J12"
		)
		(pin "E8"
		)
		(pin "J5"
		)
		(pin "J2"
		)
		(pin "G12"
		)
		(pin "G2"
		)
		(pin "M2"
		)
		(pin "D11"
		)
		(pin "J4"
		)
		(pin "K12"
		)
		(pin "K9"
		)
		(pin "L4"
		)
		(pin "L8"
		)
		(pin "L3"
		)
		(pin "E3"
		)
		(pin "F12"
		)
		(pin "M12"
		)
		(pin "A10"
		)
		(pin "L6"
		)
		(pin "D2"
		)
		(pin "H7"
		)
		(pin "J6"
		)
		(pin "C1"
		)
		(pin "J3"
		)
		(pin "A9"
		)
		(pin "K6"
		)
		(pin "G10"
		)
		(pin "B4"
		)
		(pin "D7"
		)
		(pin "L1"
		)
		(pin "H5"
		)
		(pin "J1"
		)
		(pin "L10"
		)
		(pin "L9"
		)
		(instances
			(project "com-express-7-baseboard"
				(path ""
					(reference "U45")
					(unit 4)
				)
				(path ""
					(reference "U43")
					(unit 4)
				)
			)
		)
	)
	(symbol
		(lib_id "antmicropower:GND")
		(at 307.34 170.18 0)
		(mirror y)
		(unit 1)
		(exclude_from_sim no)
		(in_bom yes)
		(on_board yes)
		(dnp no)
		(fields_autoplaced yes)
		(property "Reference" "#PWR0370"
			(at 307.34 176.53 0)
			(effects
				(font
					(size 1.27 1.27)
				)
				(justify left bottom)
				(hide yes)
			)
		)
		(property "Value" "GND"
			(at 307.34 175.26 0)
			(effects
				(font
					(size 1.27 1.27)
				)
			)
		)
		(property "Footprint" ""
			(at 307.34 170.18 0)
			(effects
				(font
					(size 1.27 1.27)
				)
				(justify left bottom)
				(hide yes)
			)
		)
		(property "Datasheet" ""
			(at 307.34 170.18 0)
			(effects
				(font
					(size 1.27 1.27)
				)
				(justify left bottom)
				(hide yes)
			)
		)
		(property "Description" ""
			(at 307.34 170.18 0)
			(effects
				(font
					(size 1.27 1.27)
				)
				(hide yes)
			)
		)
		(property "Author" "Antmicro"
			(at 298.45 177.8 0)
			(effects
				(font
					(size 1.27 1.27)
					(thickness 0.15)
				)
				(justify left bottom)
				(hide yes)
			)
		)
		(property "License" "Apache-2.0"
			(at 298.45 180.34 0)
			(effects
				(font
					(size 1.27 1.27)
					(thickness 0.15)
				)
				(justify left bottom)
				(hide yes)
			)
		)
		(pin "1"
		)
		(instances
			(project "com-express-7-baseboard"
				(path ""
					(reference "#PWR0421")
					(unit 1)
				)
				(path ""
					(reference "#PWR0370")
					(unit 1)
				)
			)
		)
	)
	(symbol
		(lib_id "antmicropower:GND")
		(at 105.41 219.71 0)
		(mirror y)
		(unit 1)
		(exclude_from_sim no)
		(in_bom yes)
		(on_board yes)
		(dnp no)
		(property "Reference" "#PWR0334"
			(at 105.41 226.06 0)
			(effects
				(font
					(size 1.27 1.27)
				)
				(justify left bottom)
				(hide yes)
			)
		)
		(property "Value" "GND"
			(at 105.41 223.52 0)
			(effects
				(font
					(size 1.27 1.27)
				)
			)
		)
		(property "Footprint" ""
			(at 105.41 219.71 0)
			(effects
				(font
					(size 1.27 1.27)
				)
				(justify left bottom)
				(hide yes)
			)
		)
		(property "Datasheet" ""
			(at 105.41 219.71 0)
			(effects
				(font
					(size 1.27 1.27)
				)
				(justify left bottom)
				(hide yes)
			)
		)
		(property "Description" ""
			(at 105.41 219.71 0)
			(effects
				(font
					(size 1.27 1.27)
				)
				(hide yes)
			)
		)
		(property "Author" "Antmicro"
			(at 96.52 227.33 0)
			(effects
				(font
					(size 1.27 1.27)
					(thickness 0.15)
				)
				(justify left bottom)
				(hide yes)
			)
		)
		(property "License" "Apache-2.0"
			(at 96.52 229.87 0)
			(effects
				(font
					(size 1.27 1.27)
					(thickness 0.15)
				)
				(justify left bottom)
				(hide yes)
			)
		)
		(pin "1"
		)
		(instances
			(project "com-express-7-baseboard"
				(path ""
					(reference "#PWR0385")
					(unit 1)
				)
				(path ""
					(reference "#PWR0334")
					(unit 1)
				)
			)
		)
	)
	(symbol
		(lib_id "antmicropower:GND")
		(at 287.02 170.18 0)
		(mirror y)
		(unit 1)
		(exclude_from_sim no)
		(in_bom yes)
		(on_board yes)
		(dnp no)
		(fields_autoplaced yes)
		(property "Reference" "#PWR0363"
			(at 287.02 176.53 0)
			(effects
				(font
					(size 1.27 1.27)
				)
				(justify left bottom)
				(hide yes)
			)
		)
		(property "Value" "GND"
			(at 287.02 175.26 0)
			(effects
				(font
					(size 1.27 1.27)
				)
			)
		)
		(property "Footprint" ""
			(at 287.02 170.18 0)
			(effects
				(font
					(size 1.27 1.27)
				)
				(justify left bottom)
				(hide yes)
			)
		)
		(property "Datasheet" ""
			(at 287.02 170.18 0)
			(effects
				(font
					(size 1.27 1.27)
				)
				(justify left bottom)
				(hide yes)
			)
		)
		(property "Description" ""
			(at 287.02 170.18 0)
			(effects
				(font
					(size 1.27 1.27)
				)
				(hide yes)
			)
		)
		(property "Author" "Antmicro"
			(at 278.13 177.8 0)
			(effects
				(font
					(size 1.27 1.27)
					(thickness 0.15)
				)
				(justify left bottom)
				(hide yes)
			)
		)
		(property "License" "Apache-2.0"
			(at 278.13 180.34 0)
			(effects
				(font
					(size 1.27 1.27)
					(thickness 0.15)
				)
				(justify left bottom)
				(hide yes)
			)
		)
		(pin "1"
		)
		(instances
			(project "com-express-7-baseboard"
				(path ""
					(reference "#PWR0414")
					(unit 1)
				)
				(path ""
					(reference "#PWR0363")
					(unit 1)
				)
			)
		)
	)
	(symbol
		(lib_id "antmicropower:+3V3")
		(at 62.23 189.23 0)
		(unit 1)
		(exclude_from_sim no)
		(in_bom yes)
		(on_board yes)
		(dnp no)
		(fields_autoplaced yes)
		(property "Reference" "#PWR0327"
			(at 77.47 189.23 0)
			(effects
				(font
					(size 1.27 1.27)
					(thickness 0.15)
				)
				(justify left bottom)
				(hide yes)
			)
		)
		(property "Value" "+3V3"
			(at 62.23 184.15 0)
			(effects
				(font
					(size 1.27 1.27)
					(thickness 0.15)
				)
			)
		)
		(property "Footprint" ""
			(at 77.47 196.85 0)
			(effects
				(font
					(size 1.27 1.27)
					(thickness 0.15)
				)
				(justify left bottom)
				(hide yes)
			)
		)
		(property "Datasheet" ""
			(at 77.47 199.39 0)
			(effects
				(font
					(size 1.27 1.27)
					(thickness 0.15)
				)
				(justify left bottom)
				(hide yes)
			)
		)
		(property "Description" ""
			(at 62.23 189.23 0)
			(effects
				(font
					(size 1.27 1.27)
				)
				(hide yes)
			)
		)
		(property "Author" "Antmicro"
			(at 77.47 191.77 0)
			(effects
				(font
					(size 1.27 1.27)
					(thickness 0.15)
				)
				(justify left bottom)
				(hide yes)
			)
		)
		(property "License" "Apache-2.0"
			(at 77.47 194.31 0)
			(effects
				(font
					(size 1.27 1.27)
					(thickness 0.15)
				)
				(justify left bottom)
				(hide yes)
			)
		)
		(pin "1"
		)
		(instances
			(project "com-express-7-baseboard"
				(path ""
					(reference "#PWR0378")
					(unit 1)
				)
				(path ""
					(reference "#PWR0327")
					(unit 1)
				)
			)
		)
	)
	(symbol
		(lib_id "antmicroResistors0402:R_10k_0402")
		(at 245.11 223.52 90)
		(unit 1)
		(exclude_from_sim no)
		(in_bom yes)
		(on_board yes)
		(dnp yes)
		(fields_autoplaced yes)
		(property "Reference" "R270"
			(at 247.65 218.44 90)
			(effects
				(font
					(size 1.27 1.27)
					(thickness 0.15)
				)
				(justify right)
			)
		)
		(property "Value" "R_10k_0402"
			(at 257.81 203.2 0)
			(effects
				(font
					(size 1.27 1.27)
					(thickness 0.15)
				)
				(justify left bottom)
				(hide yes)
			)
		)
		(property "Footprint" "antmicro-footprints:R_0402_1005Metric"
			(at 260.35 203.2 0)
			(effects
				(font
					(size 1.27 1.27)
					(thickness 0.15)
				)
				(justify left bottom)
				(hide yes)
			)
		)
		(property "Datasheet" "https://www.bourns.com/docs/product-datasheets/cr.pdf"
			(at 262.89 203.2 0)
			(effects
				(font
					(size 1.27 1.27)
					(thickness 0.15)
				)
				(justify left bottom)
				(hide yes)
			)
		)
		(property "Description" ""
			(at 245.11 223.52 0)
			(effects
				(font
					(size 1.27 1.27)
				)
				(hide yes)
			)
		)
		(property "MPN" "CR0402-FX-1002GLF"
			(at 265.43 203.2 0)
			(effects
				(font
					(size 1.27 1.27)
					(thickness 0.15)
				)
				(justify left bottom)
				(hide yes)
			)
		)
		(property "Manufacturer" "Bourns"
			(at 267.97 203.2 0)
			(effects
				(font
					(size 1.27 1.27)
					(thickness 0.15)
				)
				(justify left bottom)
				(hide yes)
			)
		)
		(property "License" "Apache-2.0"
			(at 270.51 203.2 0)
			(effects
				(font
					(size 1.27 1.27)
					(thickness 0.15)
				)
				(justify left bottom)
				(hide yes)
			)
		)
		(property "Author" "Antmicro"
			(at 273.05 203.2 0)
			(effects
				(font
					(size 1.27 1.27)
					(thickness 0.15)
				)
				(justify left bottom)
				(hide yes)
			)
		)
		(property "Val" "10k"
			(at 247.65 220.98 90)
			(effects
				(font
					(size 1.27 1.27)
					(thickness 0.15)
				)
				(justify right)
			)
		)
		(property "Tolerance" "1%"
			(at 255.27 203.2 0)
			(effects
				(font
					(size 1.27 1.27)
				)
				(justify left bottom)
				(hide yes)
			)
		)
		(property "Public" "False"
			(at 275.59 203.2 0)
			(effects
				(font
					(size 1.27 1.27)
				)
				(justify left bottom)
				(hide yes)
			)
		)
		(pin "2"
		)
		(pin "1"
		)
		(instances
			(project "com-express-7-baseboard"
				(path ""
					(reference "R304")
					(unit 1)
				)
				(path ""
					(reference "R270")
					(unit 1)
				)
			)
		)
	)
	(symbol
		(lib_id "antmicropower:+1V8")
		(at 200.66 218.44 0)
		(unit 1)
		(exclude_from_sim no)
		(in_bom yes)
		(on_board yes)
		(dnp no)
		(property "Reference" "#PWR0342"
			(at 215.9 220.98 0)
			(effects
				(font
					(size 1.27 1.27)
					(thickness 0.15)
				)
				(justify left bottom)
				(hide yes)
			)
		)
		(property "Value" "+1V8"
			(at 200.66 214.63 0)
			(effects
				(font
					(size 1.27 1.27)
					(thickness 0.15)
				)
			)
		)
		(property "Footprint" ""
			(at 215.9 226.06 0)
			(effects
				(font
					(size 1.27 1.27)
					(thickness 0.15)
				)
				(justify left bottom)
				(hide yes)
			)
		)
		(property "Datasheet" ""
			(at 215.9 228.6 0)
			(effects
				(font
					(size 1.27 1.27)
					(thickness 0.15)
				)
				(justify left bottom)
				(hide yes)
			)
		)
		(property "Description" ""
			(at 200.66 218.44 0)
			(effects
				(font
					(size 1.27 1.27)
				)
				(hide yes)
			)
		)
		(property "Author" "Antmicro"
			(at 215.9 223.52 0)
			(effects
				(font
					(size 1.27 1.27)
					(thickness 0.15)
				)
				(justify left bottom)
				(hide yes)
			)
		)
		(property "License" "Apache-2.0"
			(at 215.9 226.06 0)
			(effects
				(font
					(size 1.27 1.27)
					(thickness 0.15)
				)
				(justify left bottom)
				(hide yes)
			)
		)
		(pin "1"
		)
		(instances
			(project "com-express-7-baseboard"
				(path ""
					(reference "#PWR0393")
					(unit 1)
				)
				(path ""
					(reference "#PWR0342")
					(unit 1)
				)
			)
		)
	)
	(symbol
		(lib_id "antmicroCapacitors0402:C_100n_0402")
		(at 317.5 215.9 90)
		(unit 1)
		(exclude_from_sim no)
		(in_bom yes)
		(on_board yes)
		(dnp no)
		(fields_autoplaced yes)
		(property "Reference" "C172"
			(at 320.04 212.0836 90)
			(effects
				(font
					(size 1.27 1.27)
					(thickness 0.15)
				)
				(justify right)
			)
		)
		(property "Value" "C_100n_0402"
			(at 327.66 195.58 0)
			(effects
				(font
					(size 1.27 1.27)
					(thickness 0.15)
				)
				(justify left bottom)
				(hide yes)
			)
		)
		(property "Footprint" "antmicro-footprints:C_0402_1005Metric"
			(at 330.2 195.58 0)
			(effects
				(font
					(size 1.27 1.27)
					(thickness 0.15)
				)
				(justify left bottom)
				(hide yes)
			)
		)
		(property "Datasheet" "https://www.murata.com/products/productdetail?partno=GRM155R61H104KE14%23"
			(at 332.74 195.58 0)
			(effects
				(font
					(size 1.27 1.27)
					(thickness 0.15)
				)
				(justify left bottom)
				(hide yes)
			)
		)
		(property "Description" ""
			(at 317.5 215.9 0)
			(effects
				(font
					(size 1.27 1.27)
				)
				(hide yes)
			)
		)
		(property "MPN" "GRM155R61H104KE14D"
			(at 335.28 195.58 0)
			(effects
				(font
					(size 1.27 1.27)
					(thickness 0.15)
				)
				(justify left bottom)
				(hide yes)
			)
		)
		(property "Manufacturer" "Murata"
			(at 337.82 195.58 0)
			(effects
				(font
					(size 1.27 1.27)
					(thickness 0.15)
				)
				(justify left bottom)
				(hide yes)
			)
		)
		(property "License" "Apache-2.0"
			(at 340.36 195.58 0)
			(effects
				(font
					(size 1.27 1.27)
					(thickness 0.15)
				)
				(justify left bottom)
				(hide yes)
			)
		)
		(property "Author" "Antmicro"
			(at 342.9 195.58 0)
			(effects
				(font
					(size 1.27 1.27)
					(thickness 0.15)
				)
				(justify left bottom)
				(hide yes)
			)
		)
		(property "Val" "100n"
			(at 320.04 214.6236 90)
			(effects
				(font
					(size 1.27 1.27)
					(thickness 0.15)
				)
				(justify right)
			)
		)
		(property "Voltage" "50V"
			(at 345.44 195.58 0)
			(effects
				(font
					(size 1.27 1.27)
				)
				(justify left bottom)
				(hide yes)
			)
		)
		(property "Dielectric" "X5R"
			(at 347.98 195.58 0)
			(effects
				(font
					(size 1.27 1.27)
				)
				(justify left bottom)
				(hide yes)
			)
		)
		(property "Public" "False"
			(at 350.52 195.58 0)
			(effects
				(font
					(size 1.27 1.27)
				)
				(justify left bottom)
				(hide yes)
			)
		)
		(pin "2"
		)
		(pin "1"
		)
		(instances
			(project "com-express-7-baseboard"
				(path ""
					(reference "C199")
					(unit 1)
				)
				(path ""
					(reference "C172")
					(unit 1)
				)
			)
		)
	)
	(symbol
		(lib_id "antmicroResistors0402:R_10k_0402")
		(at 144.78 181.61 90)
		(unit 1)
		(exclude_from_sim no)
		(in_bom yes)
		(on_board yes)
		(dnp no)
		(fields_autoplaced yes)
		(property "Reference" "R259"
			(at 147.32 177.8 90)
			(effects
				(font
					(size 1.27 1.27)
					(thickness 0.15)
				)
				(justify right)
			)
		)
		(property "Value" "R_10k_0402"
			(at 157.48 161.29 0)
			(effects
				(font
					(size 1.27 1.27)
					(thickness 0.15)
				)
				(justify left bottom)
				(hide yes)
			)
		)
		(property "Footprint" "antmicro-footprints:R_0402_1005Metric"
			(at 160.02 161.29 0)
			(effects
				(font
					(size 1.27 1.27)
					(thickness 0.15)
				)
				(justify left bottom)
				(hide yes)
			)
		)
		(property "Datasheet" "https://www.bourns.com/docs/product-datasheets/cr.pdf"
			(at 162.56 161.29 0)
			(effects
				(font
					(size 1.27 1.27)
					(thickness 0.15)
				)
				(justify left bottom)
				(hide yes)
			)
		)
		(property "Description" ""
			(at 144.78 181.61 0)
			(effects
				(font
					(size 1.27 1.27)
				)
				(hide yes)
			)
		)
		(property "MPN" "CR0402-FX-1002GLF"
			(at 165.1 161.29 0)
			(effects
				(font
					(size 1.27 1.27)
					(thickness 0.15)
				)
				(justify left bottom)
				(hide yes)
			)
		)
		(property "Manufacturer" "Bourns"
			(at 167.64 161.29 0)
			(effects
				(font
					(size 1.27 1.27)
					(thickness 0.15)
				)
				(justify left bottom)
				(hide yes)
			)
		)
		(property "License" "Apache-2.0"
			(at 170.18 161.29 0)
			(effects
				(font
					(size 1.27 1.27)
					(thickness 0.15)
				)
				(justify left bottom)
				(hide yes)
			)
		)
		(property "Author" "Antmicro"
			(at 172.72 161.29 0)
			(effects
				(font
					(size 1.27 1.27)
					(thickness 0.15)
				)
				(justify left bottom)
				(hide yes)
			)
		)
		(property "Val" "10k"
			(at 147.32 180.34 90)
			(effects
				(font
					(size 1.27 1.27)
					(thickness 0.15)
				)
				(justify right)
			)
		)
		(property "Tolerance" "1%"
			(at 154.94 161.29 0)
			(effects
				(font
					(size 1.27 1.27)
				)
				(justify left bottom)
				(hide yes)
			)
		)
		(property "Public" "False"
			(at 175.26 161.29 0)
			(effects
				(font
					(size 1.27 1.27)
				)
				(justify left bottom)
				(hide yes)
			)
		)
		(pin "2"
		)
		(pin "1"
		)
		(instances
			(project "com-express-7-baseboard"
				(path ""
					(reference "R293")
					(unit 1)
				)
				(path ""
					(reference "R259")
					(unit 1)
				)
			)
		)
	)
	(symbol
		(lib_id "antmicroTestPoints:TP_0.75mm_SMD")
		(at 149.86 205.74 0)
		(mirror y)
		(unit 1)
		(exclude_from_sim no)
		(in_bom no)
		(on_board yes)
		(dnp no)
		(fields_autoplaced yes)
		(property "Reference" "TP59"
			(at 144.78 205.74 0)
			(effects
				(font
					(size 1.27 1.27)
					(thickness 0.15)
				)
				(justify left)
			)
		)
		(property "Value" "TP_0.75mm_SMD"
			(at 139.065 209.55 0)
			(effects
				(font
					(size 1.27 1.27)
					(thickness 0.15)
				)
				(justify left bottom)
				(hide yes)
			)
		)
		(property "Footprint" "antmicro-footprints:TP_SMD_0.75mm"
			(at 139.065 212.09 0)
			(effects
				(font
					(size 1.27 1.27)
					(thickness 0.15)
				)
				(justify left bottom)
				(hide yes)
			)
		)
		(property "Datasheet" ""
			(at 132.08 218.44 0)
			(effects
				(font
					(size 1.27 1.27)
					(thickness 0.15)
				)
				(justify left bottom)
				(hide yes)
			)
		)
		(property "Description" ""
			(at 149.86 205.74 0)
			(effects
				(font
					(size 1.27 1.27)
				)
				(hide yes)
			)
		)
		(property "MPN" ""
			(at 139.065 217.17 0)
			(effects
				(font
					(size 1.27 1.27)
					(thickness 0.15)
				)
				(justify left bottom)
				(hide yes)
			)
		)
		(property "Manufacturer" ""
			(at 139.065 212.09 0)
			(effects
				(font
					(size 1.27 1.27)
					(thickness 0.15)
				)
				(justify left bottom)
				(hide yes)
			)
		)
		(property "Author" "Antmicro"
			(at 139.065 214.63 0)
			(effects
				(font
					(size 1.27 1.27)
					(thickness 0.15)
				)
				(justify left bottom)
				(hide yes)
			)
		)
		(property "License" "Apache-2.0"
			(at 139.065 217.17 0)
			(effects
				(font
					(size 1.27 1.27)
					(thickness 0.15)
				)
				(justify left bottom)
				(hide yes)
			)
		)
		(property "Public" "False"
			(at 139.7 219.71 0)
			(effects
				(font
					(size 1.27 1.27)
				)
				(justify left bottom)
				(hide yes)
			)
		)
		(pin "1"
		)
		(instances
			(project "com-express-7-baseboard"
				(path ""
					(reference "TP79")
					(unit 1)
				)
				(path ""
					(reference "TP59")
					(unit 1)
				)
			)
		)
	)
	(symbol
		(lib_id "antmicropower:GND")
		(at 317.5 215.9 0)
		(mirror y)
		(unit 1)
		(exclude_from_sim no)
		(in_bom yes)
		(on_board yes)
		(dnp no)
		(fields_autoplaced yes)
		(property "Reference" "#PWR0374"
			(at 317.5 222.25 0)
			(effects
				(font
					(size 1.27 1.27)
				)
				(justify left bottom)
				(hide yes)
			)
		)
		(property "Value" "GND"
			(at 317.5 220.98 0)
			(effects
				(font
					(size 1.27 1.27)
				)
			)
		)
		(property "Footprint" ""
			(at 317.5 215.9 0)
			(effects
				(font
					(size 1.27 1.27)
				)
				(justify left bottom)
				(hide yes)
			)
		)
		(property "Datasheet" ""
			(at 317.5 215.9 0)
			(effects
				(font
					(size 1.27 1.27)
				)
				(justify left bottom)
				(hide yes)
			)
		)
		(property "Description" ""
			(at 317.5 215.9 0)
			(effects
				(font
					(size 1.27 1.27)
				)
				(hide yes)
			)
		)
		(property "Author" "Antmicro"
			(at 308.61 223.52 0)
			(effects
				(font
					(size 1.27 1.27)
					(thickness 0.15)
				)
				(justify left bottom)
				(hide yes)
			)
		)
		(property "License" "Apache-2.0"
			(at 308.61 226.06 0)
			(effects
				(font
					(size 1.27 1.27)
					(thickness 0.15)
				)
				(justify left bottom)
				(hide yes)
			)
		)
		(pin "1"
		)
		(instances
			(project "com-express-7-baseboard"
				(path ""
					(reference "#PWR0425")
					(unit 1)
				)
				(path ""
					(reference "#PWR0374")
					(unit 1)
				)
			)
		)
	)
	(symbol
		(lib_id "antmicroTestPoints:TP_0.75mm_SMD")
		(at 149.86 198.12 0)
		(mirror y)
		(unit 1)
		(exclude_from_sim no)
		(in_bom no)
		(on_board yes)
		(dnp no)
		(fields_autoplaced yes)
		(property "Reference" "TP57"
			(at 144.78 198.12 0)
			(effects
				(font
					(size 1.27 1.27)
					(thickness 0.15)
				)
				(justify left)
			)
		)
		(property "Value" "TP_0.75mm_SMD"
			(at 139.065 201.93 0)
			(effects
				(font
					(size 1.27 1.27)
					(thickness 0.15)
				)
				(justify left bottom)
				(hide yes)
			)
		)
		(property "Footprint" "antmicro-footprints:TP_SMD_0.75mm"
			(at 139.065 204.47 0)
			(effects
				(font
					(size 1.27 1.27)
					(thickness 0.15)
				)
				(justify left bottom)
				(hide yes)
			)
		)
		(property "Datasheet" ""
			(at 132.08 210.82 0)
			(effects
				(font
					(size 1.27 1.27)
					(thickness 0.15)
				)
				(justify left bottom)
				(hide yes)
			)
		)
		(property "Description" ""
			(at 149.86 198.12 0)
			(effects
				(font
					(size 1.27 1.27)
				)
				(hide yes)
			)
		)
		(property "MPN" ""
			(at 139.065 209.55 0)
			(effects
				(font
					(size 1.27 1.27)
					(thickness 0.15)
				)
				(justify left bottom)
				(hide yes)
			)
		)
		(property "Manufacturer" ""
			(at 139.065 204.47 0)
			(effects
				(font
					(size 1.27 1.27)
					(thickness 0.15)
				)
				(justify left bottom)
				(hide yes)
			)
		)
		(property "Author" "Antmicro"
			(at 139.065 207.01 0)
			(effects
				(font
					(size 1.27 1.27)
					(thickness 0.15)
				)
				(justify left bottom)
				(hide yes)
			)
		)
		(property "License" "Apache-2.0"
			(at 139.065 209.55 0)
			(effects
				(font
					(size 1.27 1.27)
					(thickness 0.15)
				)
				(justify left bottom)
				(hide yes)
			)
		)
		(property "Public" "False"
			(at 139.7 212.09 0)
			(effects
				(font
					(size 1.27 1.27)
				)
				(justify left bottom)
				(hide yes)
			)
		)
		(pin "1"
		)
		(instances
			(project "com-express-7-baseboard"
				(path ""
					(reference "TP77")
					(unit 1)
				)
				(path ""
					(reference "TP57")
					(unit 1)
				)
			)
		)
	)
	(symbol
		(lib_id "antmicropower:GND")
		(at 208.28 250.19 0)
		(mirror y)
		(unit 1)
		(exclude_from_sim no)
		(in_bom yes)
		(on_board yes)
		(dnp no)
		(fields_autoplaced yes)
		(property "Reference" "#PWR0345"
			(at 208.28 256.54 0)
			(effects
				(font
					(size 1.27 1.27)
				)
				(justify left bottom)
				(hide yes)
			)
		)
		(property "Value" "GND"
			(at 208.28 255.27 0)
			(effects
				(font
					(size 1.27 1.27)
				)
			)
		)
		(property "Footprint" ""
			(at 208.28 250.19 0)
			(effects
				(font
					(size 1.27 1.27)
				)
				(justify left bottom)
				(hide yes)
			)
		)
		(property "Datasheet" ""
			(at 208.28 250.19 0)
			(effects
				(font
					(size 1.27 1.27)
				)
				(justify left bottom)
				(hide yes)
			)
		)
		(property "Description" ""
			(at 208.28 250.19 0)
			(effects
				(font
					(size 1.27 1.27)
				)
				(hide yes)
			)
		)
		(property "Author" "Antmicro"
			(at 199.39 257.81 0)
			(effects
				(font
					(size 1.27 1.27)
					(thickness 0.15)
				)
				(justify left bottom)
				(hide yes)
			)
		)
		(property "License" "Apache-2.0"
			(at 199.39 260.35 0)
			(effects
				(font
					(size 1.27 1.27)
					(thickness 0.15)
				)
				(justify left bottom)
				(hide yes)
			)
		)
		(pin "1"
		)
		(instances
			(project "com-express-7-baseboard"
				(path ""
					(reference "#PWR0396")
					(unit 1)
				)
				(path ""
					(reference "#PWR0345")
					(unit 1)
				)
			)
		)
	)
	(symbol
		(lib_id "antmicroTestPoints:TP_0.75mm_SMD")
		(at 194.31 193.04 0)
		(unit 1)
		(exclude_from_sim no)
		(in_bom no)
		(on_board yes)
		(dnp no)
		(fields_autoplaced yes)
		(property "Reference" "TP68"
			(at 199.39 193.04 0)
			(effects
				(font
					(size 1.27 1.27)
					(thickness 0.15)
				)
				(justify left)
			)
		)
		(property "Value" "TP_0.75mm_SMD"
			(at 205.105 196.85 0)
			(effects
				(font
					(size 1.27 1.27)
					(thickness 0.15)
				)
				(justify left bottom)
				(hide yes)
			)
		)
		(property "Footprint" "antmicro-footprints:TP_SMD_0.75mm"
			(at 205.105 199.39 0)
			(effects
				(font
					(size 1.27 1.27)
					(thickness 0.15)
				)
				(justify left bottom)
				(hide yes)
			)
		)
		(property "Datasheet" ""
			(at 212.09 205.74 0)
			(effects
				(font
					(size 1.27 1.27)
					(thickness 0.15)
				)
				(justify left bottom)
				(hide yes)
			)
		)
		(property "Description" ""
			(at 194.31 193.04 0)
			(effects
				(font
					(size 1.27 1.27)
				)
				(hide yes)
			)
		)
		(property "MPN" ""
			(at 205.105 204.47 0)
			(effects
				(font
					(size 1.27 1.27)
					(thickness 0.15)
				)
				(justify left bottom)
				(hide yes)
			)
		)
		(property "Manufacturer" ""
			(at 205.105 199.39 0)
			(effects
				(font
					(size 1.27 1.27)
					(thickness 0.15)
				)
				(justify left bottom)
				(hide yes)
			)
		)
		(property "Author" "Antmicro"
			(at 205.105 201.93 0)
			(effects
				(font
					(size 1.27 1.27)
					(thickness 0.15)
				)
				(justify left bottom)
				(hide yes)
			)
		)
		(property "License" "Apache-2.0"
			(at 205.105 204.47 0)
			(effects
				(font
					(size 1.27 1.27)
					(thickness 0.15)
				)
				(justify left bottom)
				(hide yes)
			)
		)
		(property "Public" "False"
			(at 204.47 207.01 0)
			(effects
				(font
					(size 1.27 1.27)
				)
				(justify left bottom)
				(hide yes)
			)
		)
		(pin "1"
		)
		(instances
			(project "com-express-7-baseboard"
				(path ""
					(reference "TP88")
					(unit 1)
				)
				(path ""
					(reference "TP68")
					(unit 1)
				)
			)
		)
	)
	(symbol
		(lib_id "antmicroResistors0402:R_10k_0402")
		(at 208.28 250.19 90)
		(unit 1)
		(exclude_from_sim no)
		(in_bom yes)
		(on_board yes)
		(dnp no)
		(property "Reference" "R265"
			(at 209.55 246.38 90)
			(effects
				(font
					(size 1.27 1.27)
					(thickness 0.15)
				)
				(justify right)
			)
		)
		(property "Value" "R_10k_0402"
			(at 220.98 229.87 0)
			(effects
				(font
					(size 1.27 1.27)
					(thickness 0.15)
				)
				(justify left bottom)
				(hide yes)
			)
		)
		(property "Footprint" "antmicro-footprints:R_0402_1005Metric"
			(at 223.52 229.87 0)
			(effects
				(font
					(size 1.27 1.27)
					(thickness 0.15)
				)
				(justify left bottom)
				(hide yes)
			)
		)
		(property "Datasheet" "https://www.bourns.com/docs/product-datasheets/cr.pdf"
			(at 226.06 229.87 0)
			(effects
				(font
					(size 1.27 1.27)
					(thickness 0.15)
				)
				(justify left bottom)
				(hide yes)
			)
		)
		(property "Description" ""
			(at 208.28 250.19 0)
			(effects
				(font
					(size 1.27 1.27)
				)
				(hide yes)
			)
		)
		(property "MPN" "CR0402-FX-1002GLF"
			(at 228.6 229.87 0)
			(effects
				(font
					(size 1.27 1.27)
					(thickness 0.15)
				)
				(justify left bottom)
				(hide yes)
			)
		)
		(property "Manufacturer" "Bourns"
			(at 231.14 229.87 0)
			(effects
				(font
					(size 1.27 1.27)
					(thickness 0.15)
				)
				(justify left bottom)
				(hide yes)
			)
		)
		(property "License" "Apache-2.0"
			(at 233.68 229.87 0)
			(effects
				(font
					(size 1.27 1.27)
					(thickness 0.15)
				)
				(justify left bottom)
				(hide yes)
			)
		)
		(property "Author" "Antmicro"
			(at 236.22 229.87 0)
			(effects
				(font
					(size 1.27 1.27)
					(thickness 0.15)
				)
				(justify left bottom)
				(hide yes)
			)
		)
		(property "Val" "10k"
			(at 209.55 248.92 90)
			(effects
				(font
					(size 1.27 1.27)
					(thickness 0.15)
				)
				(justify right)
			)
		)
		(property "Tolerance" "1%"
			(at 218.44 229.87 0)
			(effects
				(font
					(size 1.27 1.27)
				)
				(justify left bottom)
				(hide yes)
			)
		)
		(property "Public" "False"
			(at 238.76 229.87 0)
			(effects
				(font
					(size 1.27 1.27)
				)
				(justify left bottom)
				(hide yes)
			)
		)
		(pin "2"
		)
		(pin "1"
		)
		(instances
			(project "com-express-7-baseboard"
				(path ""
					(reference "R299")
					(unit 1)
				)
				(path ""
					(reference "R265")
					(unit 1)
				)
			)
		)
	)
	(symbol
		(lib_id "antmicropower:GND")
		(at 276.86 193.04 0)
		(mirror y)
		(unit 1)
		(exclude_from_sim no)
		(in_bom yes)
		(on_board yes)
		(dnp no)
		(fields_autoplaced yes)
		(property "Reference" "#PWR0358"
			(at 276.86 199.39 0)
			(effects
				(font
					(size 1.27 1.27)
				)
				(justify left bottom)
				(hide yes)
			)
		)
		(property "Value" "GND"
			(at 276.86 198.12 0)
			(effects
				(font
					(size 1.27 1.27)
				)
			)
		)
		(property "Footprint" ""
			(at 276.86 193.04 0)
			(effects
				(font
					(size 1.27 1.27)
				)
				(justify left bottom)
				(hide yes)
			)
		)
		(property "Datasheet" ""
			(at 276.86 193.04 0)
			(effects
				(font
					(size 1.27 1.27)
				)
				(justify left bottom)
				(hide yes)
			)
		)
		(property "Description" ""
			(at 276.86 193.04 0)
			(effects
				(font
					(size 1.27 1.27)
				)
				(hide yes)
			)
		)
		(property "Author" "Antmicro"
			(at 267.97 200.66 0)
			(effects
				(font
					(size 1.27 1.27)
					(thickness 0.15)
				)
				(justify left bottom)
				(hide yes)
			)
		)
		(property "License" "Apache-2.0"
			(at 267.97 203.2 0)
			(effects
				(font
					(size 1.27 1.27)
					(thickness 0.15)
				)
				(justify left bottom)
				(hide yes)
			)
		)
		(pin "1"
		)
		(instances
			(project "com-express-7-baseboard"
				(path ""
					(reference "#PWR0409")
					(unit 1)
				)
				(path ""
					(reference "#PWR0358")
					(unit 1)
				)
			)
		)
	)
	(symbol
		(lib_id "antmicropower:+1V0")
		(at 261.62 185.42 0)
		(unit 1)
		(exclude_from_sim no)
		(in_bom yes)
		(on_board yes)
		(dnp no)
		(property "Reference" "#PWR0351"
			(at 261.62 189.23 0)
			(effects
				(font
					(size 1.27 1.27)
				)
				(hide yes)
			)
		)
		(property "Value" "+1V0"
			(at 261.62 181.61 0)
			(effects
				(font
					(size 1.27 1.27)
				)
			)
		)
		(property "Footprint" ""
			(at 261.62 185.42 0)
			(effects
				(font
					(size 1.27 1.27)
				)
				(hide yes)
			)
		)
		(property "Datasheet" ""
			(at 261.62 185.42 0)
			(effects
				(font
					(size 1.27 1.27)
				)
				(hide yes)
			)
		)
		(property "Description" ""
			(at 261.62 185.42 0)
			(effects
				(font
					(size 1.27 1.27)
				)
				(hide yes)
			)
		)
		(pin "1"
		)
		(instances
			(project "com-express-7-baseboard"
				(path ""
					(reference "#PWR0402")
					(unit 1)
				)
				(path ""
					(reference "#PWR0351")
					(unit 1)
				)
			)
		)
	)
	(symbol
		(lib_id "antmicroResistors0402:R_100k_0402")
		(at 69.85 193.04 0)
		(unit 1)
		(exclude_from_sim no)
		(in_bom yes)
		(on_board yes)
		(dnp no)
		(property "Reference" "R246"
			(at 77.47 191.77 0)
			(effects
				(font
					(size 1.27 1.27)
					(thickness 0.15)
				)
			)
		)
		(property "Value" "R_100k_0402"
			(at 90.17 205.74 0)
			(effects
				(font
					(size 1.27 1.27)
					(thickness 0.15)
				)
				(justify left bottom)
				(hide yes)
			)
		)
		(property "Footprint" "antmicro-footprints:R_0402_1005Metric"
			(at 90.17 208.28 0)
			(effects
				(font
					(size 1.27 1.27)
					(thickness 0.15)
				)
				(justify left bottom)
				(hide yes)
			)
		)
		(property "Datasheet" "https://www.bourns.com/docs/product-datasheets/cr.pdf"
			(at 90.17 210.82 0)
			(effects
				(font
					(size 1.27 1.27)
					(thickness 0.15)
				)
				(justify left bottom)
				(hide yes)
			)
		)
		(property "Description" ""
			(at 69.85 193.04 0)
			(effects
				(font
					(size 1.27 1.27)
				)
				(hide yes)
			)
		)
		(property "MPN" "CR0402-FX-1003GLF"
			(at 90.17 213.36 0)
			(effects
				(font
					(size 1.27 1.27)
					(thickness 0.15)
				)
				(justify left bottom)
				(hide yes)
			)
		)
		(property "Manufacturer" "Bourns"
			(at 90.17 215.9 0)
			(effects
				(font
					(size 1.27 1.27)
					(thickness 0.15)
				)
				(justify left bottom)
				(hide yes)
			)
		)
		(property "License" "Apache-2.0"
			(at 90.17 218.44 0)
			(effects
				(font
					(size 1.27 1.27)
					(thickness 0.15)
				)
				(justify left bottom)
				(hide yes)
			)
		)
		(property "Author" "Antmicro"
			(at 90.17 220.98 0)
			(effects
				(font
					(size 1.27 1.27)
					(thickness 0.15)
				)
				(justify left bottom)
				(hide yes)
			)
		)
		(property "Val" "100k"
			(at 77.47 194.31 0)
			(effects
				(font
					(size 1.27 1.27)
					(thickness 0.15)
				)
			)
		)
		(property "Tolerance" "1%"
			(at 90.17 203.2 0)
			(effects
				(font
					(size 1.27 1.27)
				)
				(justify left bottom)
				(hide yes)
			)
		)
		(property "Public" "False"
			(at 90.17 223.52 0)
			(effects
				(font
					(size 1.27 1.27)
				)
				(justify left bottom)
				(hide yes)
			)
		)
		(pin "2"
		)
		(pin "1"
		)
		(instances
			(project "com-express-7-baseboard"
				(path ""
					(reference "R280")
					(unit 1)
				)
				(path ""
					(reference "R246")
					(unit 1)
				)
			)
		)
	)
	(symbol
		(lib_id "antmicropower:GND")
		(at 317.5 170.18 0)
		(mirror y)
		(unit 1)
		(exclude_from_sim no)
		(in_bom yes)
		(on_board yes)
		(dnp no)
		(fields_autoplaced yes)
		(property "Reference" "#PWR0373"
			(at 317.5 176.53 0)
			(effects
				(font
					(size 1.27 1.27)
				)
				(justify left bottom)
				(hide yes)
			)
		)
		(property "Value" "GND"
			(at 317.5 175.26 0)
			(effects
				(font
					(size 1.27 1.27)
				)
			)
		)
		(property "Footprint" ""
			(at 317.5 170.18 0)
			(effects
				(font
					(size 1.27 1.27)
				)
				(justify left bottom)
				(hide yes)
			)
		)
		(property "Datasheet" ""
			(at 317.5 170.18 0)
			(effects
				(font
					(size 1.27 1.27)
				)
				(justify left bottom)
				(hide yes)
			)
		)
		(property "Description" ""
			(at 317.5 170.18 0)
			(effects
				(font
					(size 1.27 1.27)
				)
				(hide yes)
			)
		)
		(property "Author" "Antmicro"
			(at 308.61 177.8 0)
			(effects
				(font
					(size 1.27 1.27)
					(thickness 0.15)
				)
				(justify left bottom)
				(hide yes)
			)
		)
		(property "License" "Apache-2.0"
			(at 308.61 180.34 0)
			(effects
				(font
					(size 1.27 1.27)
					(thickness 0.15)
				)
				(justify left bottom)
				(hide yes)
			)
		)
		(pin "1"
		)
		(instances
			(project "com-express-7-baseboard"
				(path ""
					(reference "#PWR0424")
					(unit 1)
				)
				(path ""
					(reference "#PWR0373")
					(unit 1)
				)
			)
		)
	)
	(symbol
		(lib_id "antmicroCapacitors0402:C_100n_0402")
		(at 276.86 193.04 90)
		(unit 1)
		(exclude_from_sim no)
		(in_bom yes)
		(on_board yes)
		(dnp no)
		(fields_autoplaced yes)
		(property "Reference" "C158"
			(at 279.4 189.2236 90)
			(effects
				(font
					(size 1.27 1.27)
					(thickness 0.15)
				)
				(justify right)
			)
		)
		(property "Value" "C_100n_0402"
			(at 287.02 172.72 0)
			(effects
				(font
					(size 1.27 1.27)
					(thickness 0.15)
				)
				(justify left bottom)
				(hide yes)
			)
		)
		(property "Footprint" "antmicro-footprints:C_0402_1005Metric"
			(at 289.56 172.72 0)
			(effects
				(font
					(size 1.27 1.27)
					(thickness 0.15)
				)
				(justify left bottom)
				(hide yes)
			)
		)
		(property "Datasheet" "https://www.murata.com/products/productdetail?partno=GRM155R61H104KE14%23"
			(at 292.1 172.72 0)
			(effects
				(font
					(size 1.27 1.27)
					(thickness 0.15)
				)
				(justify left bottom)
				(hide yes)
			)
		)
		(property "Description" ""
			(at 276.86 193.04 0)
			(effects
				(font
					(size 1.27 1.27)
				)
				(hide yes)
			)
		)
		(property "MPN" "GRM155R61H104KE14D"
			(at 294.64 172.72 0)
			(effects
				(font
					(size 1.27 1.27)
					(thickness 0.15)
				)
				(justify left bottom)
				(hide yes)
			)
		)
		(property "Manufacturer" "Murata"
			(at 297.18 172.72 0)
			(effects
				(font
					(size 1.27 1.27)
					(thickness 0.15)
				)
				(justify left bottom)
				(hide yes)
			)
		)
		(property "License" "Apache-2.0"
			(at 299.72 172.72 0)
			(effects
				(font
					(size 1.27 1.27)
					(thickness 0.15)
				)
				(justify left bottom)
				(hide yes)
			)
		)
		(property "Author" "Antmicro"
			(at 302.26 172.72 0)
			(effects
				(font
					(size 1.27 1.27)
					(thickness 0.15)
				)
				(justify left bottom)
				(hide yes)
			)
		)
		(property "Val" "100n"
			(at 279.4 191.7636 90)
			(effects
				(font
					(size 1.27 1.27)
					(thickness 0.15)
				)
				(justify right)
			)
		)
		(property "Voltage" "50V"
			(at 304.8 172.72 0)
			(effects
				(font
					(size 1.27 1.27)
				)
				(justify left bottom)
				(hide yes)
			)
		)
		(property "Dielectric" "X5R"
			(at 307.34 172.72 0)
			(effects
				(font
					(size 1.27 1.27)
				)
				(justify left bottom)
				(hide yes)
			)
		)
		(property "Public" "False"
			(at 309.88 172.72 0)
			(effects
				(font
					(size 1.27 1.27)
				)
				(justify left bottom)
				(hide yes)
			)
		)
		(pin "2"
		)
		(pin "1"
		)
		(instances
			(project "com-express-7-baseboard"
				(path ""
					(reference "C185")
					(unit 1)
				)
				(path ""
					(reference "C158")
					(unit 1)
				)
			)
		)
	)
	(symbol
		(lib_id "antmicroTestPoints:TP_0.75mm_SMD")
		(at 186.69 116.84 0)
		(unit 1)
		(exclude_from_sim no)
		(in_bom no)
		(on_board yes)
		(dnp no)
		(fields_autoplaced yes)
		(property "Reference" "TP71"
			(at 191.77 116.84 0)
			(effects
				(font
					(size 1.27 1.27)
					(thickness 0.15)
				)
				(justify left)
			)
		)
		(property "Value" "TP_0.75mm_SMD"
			(at 197.485 120.65 0)
			(effects
				(font
					(size 1.27 1.27)
					(thickness 0.15)
				)
				(justify left bottom)
				(hide yes)
			)
		)
		(property "Footprint" "antmicro-footprints:TP_SMD_0.75mm"
			(at 197.485 123.19 0)
			(effects
				(font
					(size 1.27 1.27)
					(thickness 0.15)
				)
				(justify left bottom)
				(hide yes)
			)
		)
		(property "Datasheet" ""
			(at 204.47 129.54 0)
			(effects
				(font
					(size 1.27 1.27)
					(thickness 0.15)
				)
				(justify left bottom)
				(hide yes)
			)
		)
		(property "Description" ""
			(at 186.69 116.84 0)
			(effects
				(font
					(size 1.27 1.27)
				)
				(hide yes)
			)
		)
		(property "MPN" ""
			(at 197.485 128.27 0)
			(effects
				(font
					(size 1.27 1.27)
					(thickness 0.15)
				)
				(justify left bottom)
				(hide yes)
			)
		)
		(property "Manufacturer" ""
			(at 197.485 123.19 0)
			(effects
				(font
					(size 1.27 1.27)
					(thickness 0.15)
				)
				(justify left bottom)
				(hide yes)
			)
		)
		(property "Author" "Antmicro"
			(at 197.485 125.73 0)
			(effects
				(font
					(size 1.27 1.27)
					(thickness 0.15)
				)
				(justify left bottom)
				(hide yes)
			)
		)
		(property "License" "Apache-2.0"
			(at 197.485 128.27 0)
			(effects
				(font
					(size 1.27 1.27)
					(thickness 0.15)
				)
				(justify left bottom)
				(hide yes)
			)
		)
		(property "Public" "False"
			(at 196.85 130.81 0)
			(effects
				(font
					(size 1.27 1.27)
				)
				(justify left bottom)
				(hide yes)
			)
		)
		(pin "1"
		)
		(instances
			(project "com-express-7-baseboard"
				(path ""
					(reference "TP91")
					(unit 1)
				)
				(path ""
					(reference "TP71")
					(unit 1)
				)
			)
		)
	)
	(symbol
		(lib_id "antmicroCapacitors0402:C_100n_0402")
		(at 62.23 196.85 90)
		(unit 1)
		(exclude_from_sim no)
		(in_bom yes)
		(on_board yes)
		(dnp no)
		(fields_autoplaced yes)
		(property "Reference" "C148"
			(at 59.69 193.0335 90)
			(effects
				(font
					(size 1.27 1.27)
				)
				(justify left)
			)
		)
		(property "Value" "C_100n_0402"
			(at 66.04 196.85 0)
			(effects
				(font
					(size 1.27 1.27)
				)
				(justify left bottom)
				(hide yes)
			)
		)
		(property "Footprint" "antmicro-footprints:C_0402_1005Metric"
			(at 57.15 191.77 0)
			(effects
				(font
					(size 1.524 1.524)
				)
				(justify left bottom)
				(hide yes)
			)
		)
		(property "Datasheet" "https://www.murata.com/products/productdetail?partno=GRM155R61H104KE14%23"
			(at 62.23 196.85 0)
			(effects
				(font
					(size 1.27 1.27)
				)
				(justify left bottom)
				(hide yes)
			)
		)
		(property "Description" ""
			(at 62.23 196.85 0)
			(effects
				(font
					(size 1.27 1.27)
				)
				(hide yes)
			)
		)
		(property "Manufacturer" "Murata"
			(at 52.07 191.77 0)
			(effects
				(font
					(size 1.524 1.524)
				)
				(justify left bottom)
				(hide yes)
			)
		)
		(property "MPN" "GRM155R61H104KE14D"
			(at 54.61 191.77 0)
			(effects
				(font
					(size 1.524 1.524)
				)
				(justify left bottom)
				(hide yes)
			)
		)
		(property "Val" "100n"
			(at 59.69 195.5735 90)
			(effects
				(font
					(size 1.27 1.27)
				)
				(justify left)
			)
		)
		(property "License" "Apache-2.0"
			(at 85.09 176.53 0)
			(effects
				(font
					(size 1.27 1.27)
					(thickness 0.15)
				)
				(justify left bottom)
				(hide yes)
			)
		)
		(property "Author" "Antmicro"
			(at 87.63 176.53 0)
			(effects
				(font
					(size 1.27 1.27)
					(thickness 0.15)
				)
				(justify left bottom)
				(hide yes)
			)
		)
		(property "Voltage" "50V"
			(at 90.17 176.53 0)
			(effects
				(font
					(size 1.27 1.27)
				)
				(justify left bottom)
				(hide yes)
			)
		)
		(property "Dielectric" "X5R"
			(at 92.71 176.53 0)
			(effects
				(font
					(size 1.27 1.27)
				)
				(justify left bottom)
				(hide yes)
			)
		)
		(property "Public" "False"
			(at 95.25 176.53 0)
			(effects
				(font
					(size 1.27 1.27)
				)
				(justify left bottom)
				(hide yes)
			)
		)
		(pin "1"
		)
		(pin "2"
		)
		(instances
			(project "com-express-7-baseboard"
				(path ""
					(reference "C175")
					(unit 1)
				)
				(path ""
					(reference "C148")
					(unit 1)
				)
			)
		)
	)
	(symbol
		(lib_id "antmicroLogicTranslatorsLevelShifters:NTS0102_TSSOP")
		(at 100.33 226.06 0)
		(mirror y)
		(unit 1)
		(exclude_from_sim no)
		(in_bom yes)
		(on_board yes)
		(dnp no)
		(fields_autoplaced yes)
		(property "Reference" "U42"
			(at 90.17 218.44 0)
			(effects
				(font
					(size 1.27 1.27)
					(thickness 0.15)
				)
			)
		)
		(property "Value" "NTS0102_TSSOP"
			(at 90.17 220.98 0)
			(effects
				(font
					(size 1.27 1.27)
					(thickness 0.15)
				)
				(hide yes)
			)
		)
		(property "Footprint" "antmicro-footprints:TSSOP-8_3x3mm_P0.65mm"
			(at 64.77 234.95 0)
			(effects
				(font
					(size 1.27 1.27)
					(thickness 0.15)
				)
				(justify left bottom)
				(hide yes)
			)
		)
		(property "Datasheet" "https://www.mouser.com/datasheet/2/302/NTS0102-1127324.pdf"
			(at 64.77 237.49 0)
			(effects
				(font
					(size 1.27 1.27)
					(thickness 0.15)
				)
				(justify left bottom)
				(hide yes)
			)
		)
		(property "Description" ""
			(at 100.33 226.06 0)
			(effects
				(font
					(size 1.27 1.27)
				)
				(hide yes)
			)
		)
		(property "MPN" "NTS0102DP"
			(at 90.17 220.98 0)
			(effects
				(font
					(size 1.27 1.27)
					(thickness 0.15)
				)
			)
		)
		(property "Manufacturer" "NXP"
			(at 64.77 242.57 0)
			(effects
				(font
					(size 1.27 1.27)
					(thickness 0.15)
				)
				(justify left bottom)
				(hide yes)
			)
		)
		(property "Author" "Antmicro"
			(at 64.77 245.11 0)
			(effects
				(font
					(size 1.27 1.27)
					(thickness 0.15)
				)
				(justify left bottom)
				(hide yes)
			)
		)
		(property "License" "Apache-2.0"
			(at 64.77 247.65 0)
			(effects
				(font
					(size 1.27 1.27)
					(thickness 0.15)
				)
				(justify left bottom)
				(hide yes)
			)
		)
		(pin "8"
		)
		(pin "3"
		)
		(pin "2"
		)
		(pin "6"
		)
		(pin "7"
		)
		(pin "5"
		)
		(pin "1"
		)
		(pin "4"
		)
		(instances
			(project "com-express-7-baseboard"
				(path ""
					(reference "U44")
					(unit 1)
				)
				(path ""
					(reference "U42")
					(unit 1)
				)
			)
		)
	)
	(symbol
		(lib_id "antmicroInterfaceControllers:TLK10232CTR")
		(at 181.61 71.12 0)
		(mirror y)
		(unit 1)
		(exclude_from_sim no)
		(in_bom yes)
		(on_board yes)
		(dnp no)
		(property "Reference" "U43"
			(at 166.37 63.5 0)
			(effects
				(font
					(size 1.27 1.27)
					(thickness 0.15)
				)
			)
		)
		(property "Value" "TLK10232CTR"
			(at 134.62 81.28 0)
			(effects
				(font
					(size 1.27 1.27)
					(thickness 0.15)
				)
				(justify left bottom)
				(hide yes)
			)
		)
		(property "Footprint" "antmicro-footprints:BGA-144_12x12_13.05x13.05mm_P1.0mm"
			(at 134.62 83.82 0)
			(effects
				(font
					(size 1.27 1.27)
					(thickness 0.15)
				)
				(justify left bottom)
				(hide yes)
			)
		)
		(property "Datasheet" "https://www.ti.com/lit/ds/symlink/tlk10232.pdf?ts=1712150848075&ref_url=https%253A%252F%252Fwww.mouser.pl%252F"
			(at 134.62 86.36 0)
			(effects
				(font
					(size 1.27 1.27)
					(thickness 0.15)
				)
				(justify left bottom)
				(hide yes)
			)
		)
		(property "Description" ""
			(at 181.61 71.12 0)
			(effects
				(font
					(size 1.27 1.27)
				)
				(hide yes)
			)
		)
		(property "MPN" "TLK10232CTR"
			(at 166.37 66.04 0)
			(effects
				(font
					(size 1.27 1.27)
					(thickness 0.15)
				)
			)
		)
		(property "Manufacturer" "Texas Instruments"
			(at 134.62 76.2 0)
			(effects
				(font
					(size 1.27 1.27)
					(thickness 0.15)
				)
				(justify left bottom)
				(hide yes)
			)
		)
		(property "Author" "Antmicro"
			(at 134.62 88.9 0)
			(effects
				(font
					(size 1.27 1.27)
					(thickness 0.15)
				)
				(justify left bottom)
				(hide yes)
			)
		)
		(property "License" "Apache-2.0"
			(at 134.62 91.44 0)
			(effects
				(font
					(size 1.27 1.27)
					(thickness 0.15)
				)
				(justify left bottom)
				(hide yes)
			)
		)
		(pin "J2"
		)
		(pin "A10"
		)
		(pin "E6"
		)
		(pin "A9"
		)
		(pin "F2"
		)
		(pin "B2"
		)
		(pin "J6"
		)
		(pin "J8"
		)
		(pin "E2"
		)
		(pin "J12"
		)
		(pin "G4"
		)
		(pin "A12"
		)
		(pin "K3"
		)
		(pin "F3"
		)
		(pin "C11"
		)
		(pin "M12"
		)
		(pin "F9"
		)
		(pin "B12"
		)
		(pin "K12"
		)
		(pin "C4"
		)
		(pin "B1"
		)
		(pin "D5"
		)
		(pin "D4"
		)
		(pin "F11"
		)
		(pin "B6"
		)
		(pin "E1"
		)
		(pin "E12"
		)
		(pin "K5"
		)
		(pin "M10"
		)
		(pin "L11"
		)
		(pin "H9"
		)
		(pin "E3"
		)
		(pin "B7"
		)
		(pin "D7"
		)
		(pin "A5"
		)
		(pin "K10"
		)
		(pin "G7"
		)
		(pin "L8"
		)
		(pin "G9"
		)
		(pin "G5"
		)
		(pin "E5"
		)
		(pin "M3"
		)
		(pin "M1"
		)
		(pin "A2"
		)
		(pin "E10"
		)
		(pin "D8"
		)
		(pin "B11"
		)
		(pin "J1"
		)
		(pin "D6"
		)
		(pin "M6"
		)
		(pin "J3"
		)
		(pin "M2"
		)
		(pin "L10"
		)
		(pin "F10"
		)
		(pin "D10"
		)
		(pin "E4"
		)
		(pin "F4"
		)
		(pin "E11"
		)
		(pin "A11"
		)
		(pin "H12"
		)
		(pin "G1"
		)
		(pin "H1"
		)
		(pin "K7"
		)
		(pin "G8"
		)
		(pin "H4"
		)
		(pin "K2"
		)
		(pin "L3"
		)
		(pin "F6"
		)
		(pin "H6"
		)
		(pin "G10"
		)
		(pin "H11"
		)
		(pin "J4"
		)
		(pin "K4"
		)
		(pin "H3"
		)
		(pin "J10"
		)
		(pin "F12"
		)
		(pin "H5"
		)
		(pin "M4"
		)
		(pin "B3"
		)
		(pin "B4"
		)
		(pin "M9"
		)
		(pin "K6"
		)
		(pin "M8"
		)
		(pin "D3"
		)
		(pin "H10"
		)
		(pin "F8"
		)
		(pin "K8"
		)
		(pin "F7"
		)
		(pin "C5"
		)
		(pin "L1"
		)
		(pin "E9"
		)
		(pin "L2"
		)
		(pin "L5"
		)
		(pin "L6"
		)
		(pin "B8"
		)
		(pin "L12"
		)
		(pin "C9"
		)
		(pin "F5"
		)
		(pin "D2"
		)
		(pin "D11"
		)
		(pin "D1"
		)
		(pin "C8"
		)
		(pin "H2"
		)
		(pin "M11"
		)
		(pin "D12"
		)
		(pin "D9"
		)
		(pin "A1"
		)
		(pin "G12"
		)
		(pin "C2"
		)
		(pin "A8"
		)
		(pin "B10"
		)
		(pin "A7"
		)
		(pin "C10"
		)
		(pin "A4"
		)
		(pin "A3"
		)
		(pin "B5"
		)
		(pin "L4"
		)
		(pin "B9"
		)
		(pin "J5"
		)
		(pin "M5"
		)
		(pin "G2"
		)
		(pin "J11"
		)
		(pin "A6"
		)
		(pin "K9"
		)
		(pin "C3"
		)
		(pin "G6"
		)
		(pin "L7"
		)
		(pin "L9"
		)
		(pin "C12"
		)
		(pin "C1"
		)
		(pin "E7"
		)
		(pin "H7"
		)
		(pin "M7"
		)
		(pin "C7"
		)
		(pin "F1"
		)
		(pin "J7"
		)
		(pin "G3"
		)
		(pin "J9"
		)
		(pin "K11"
		)
		(pin "E8"
		)
		(pin "H8"
		)
		(pin "K1"
		)
		(pin "C6"
		)
		(pin "G11"
		)
		(instances
			(project "com-express-7-baseboard"
				(path ""
					(reference "U45")
					(unit 1)
				)
				(path ""
					(reference "U43")
					(unit 1)
				)
			)
		)
	)
	(symbol
		(lib_id "antmicroResistors0402:R_10k_0402")
		(at 125.73 213.36 90)
		(unit 1)
		(exclude_from_sim no)
		(in_bom yes)
		(on_board yes)
		(dnp yes)
		(fields_autoplaced yes)
		(property "Reference" "R252"
			(at 123.19 208.28 90)
			(effects
				(font
					(size 1.27 1.27)
					(thickness 0.15)
				)
				(justify left)
			)
		)
		(property "Value" "R_10k_0402"
			(at 138.43 193.04 0)
			(effects
				(font
					(size 1.27 1.27)
					(thickness 0.15)
				)
				(justify left bottom)
				(hide yes)
			)
		)
		(property "Footprint" "antmicro-footprints:R_0402_1005Metric"
			(at 140.97 193.04 0)
			(effects
				(font
					(size 1.27 1.27)
					(thickness 0.15)
				)
				(justify left bottom)
				(hide yes)
			)
		)
		(property "Datasheet" "https://www.bourns.com/docs/product-datasheets/cr.pdf"
			(at 143.51 193.04 0)
			(effects
				(font
					(size 1.27 1.27)
					(thickness 0.15)
				)
				(justify left bottom)
				(hide yes)
			)
		)
		(property "Description" ""
			(at 125.73 213.36 0)
			(effects
				(font
					(size 1.27 1.27)
				)
				(hide yes)
			)
		)
		(property "MPN" "CR0402-FX-1002GLF"
			(at 146.05 193.04 0)
			(effects
				(font
					(size 1.27 1.27)
					(thickness 0.15)
				)
				(justify left bottom)
				(hide yes)
			)
		)
		(property "Manufacturer" "Bourns"
			(at 148.59 193.04 0)
			(effects
				(font
					(size 1.27 1.27)
					(thickness 0.15)
				)
				(justify left bottom)
				(hide yes)
			)
		)
		(property "License" "Apache-2.0"
			(at 151.13 193.04 0)
			(effects
				(font
					(size 1.27 1.27)
					(thickness 0.15)
				)
				(justify left bottom)
				(hide yes)
			)
		)
		(property "Author" "Antmicro"
			(at 153.67 193.04 0)
			(effects
				(font
					(size 1.27 1.27)
					(thickness 0.15)
				)
				(justify left bottom)
				(hide yes)
			)
		)
		(property "Val" "10k"
			(at 123.19 210.82 90)
			(effects
				(font
					(size 1.27 1.27)
					(thickness 0.15)
				)
				(justify left)
			)
		)
		(property "Tolerance" "1%"
			(at 135.89 193.04 0)
			(effects
				(font
					(size 1.27 1.27)
				)
				(justify left bottom)
				(hide yes)
			)
		)
		(property "Public" "False"
			(at 156.21 193.04 0)
			(effects
				(font
					(size 1.27 1.27)
				)
				(justify left bottom)
				(hide yes)
			)
		)
		(pin "2"
		)
		(pin "1"
		)
		(instances
			(project "com-express-7-baseboard"
				(path ""
					(reference "R286")
					(unit 1)
				)
				(path ""
					(reference "R252")
					(unit 1)
				)
			)
		)
	)
	(symbol
		(lib_id "antmicropower:+1V0")
		(at 276.86 207.01 0)
		(unit 1)
		(exclude_from_sim no)
		(in_bom yes)
		(on_board yes)
		(dnp no)
		(property "Reference" "#PWR0359"
			(at 276.86 210.82 0)
			(effects
				(font
					(size 1.27 1.27)
				)
				(hide yes)
			)
		)
		(property "Value" "+1V0"
			(at 276.86 203.2 0)
			(effects
				(font
					(size 1.27 1.27)
				)
			)
		)
		(property "Footprint" ""
			(at 276.86 207.01 0)
			(effects
				(font
					(size 1.27 1.27)
				)
				(hide yes)
			)
		)
		(property "Datasheet" ""
			(at 276.86 207.01 0)
			(effects
				(font
					(size 1.27 1.27)
				)
				(hide yes)
			)
		)
		(property "Description" ""
			(at 276.86 207.01 0)
			(effects
				(font
					(size 1.27 1.27)
				)
				(hide yes)
			)
		)
		(pin "1"
		)
		(instances
			(project "com-express-7-baseboard"
				(path ""
					(reference "#PWR0410")
					(unit 1)
				)
				(path ""
					(reference "#PWR0359")
					(unit 1)
				)
			)
		)
	)
	(symbol
		(lib_id "antmicroResistorsmisc:R_0R_0201")
		(at 110.49 67.31 90)
		(unit 1)
		(exclude_from_sim no)
		(in_bom yes)
		(on_board yes)
		(dnp yes)
		(property "Reference" "R250"
			(at 111.76 59.69 0)
			(effects
				(font
					(size 1.27 1.27)
					(thickness 0.15)
				)
			)
		)
		(property "Value" "R_0R_0201"
			(at 123.19 46.99 0)
			(effects
				(font
					(size 1.27 1.27)
					(thickness 0.15)
				)
				(justify left bottom)
				(hide yes)
			)
		)
		(property "Footprint" "antmicro-footprints:R_0201"
			(at 125.73 46.99 0)
			(effects
				(font
					(size 1.27 1.27)
					(thickness 0.15)
				)
				(justify left bottom)
				(hide yes)
			)
		)
		(property "Datasheet" "https://www.bourns.com/docs/product-datasheets/cr.pdf"
			(at 128.27 46.99 0)
			(effects
				(font
					(size 1.27 1.27)
					(thickness 0.15)
				)
				(justify left bottom)
				(hide yes)
			)
		)
		(property "Description" ""
			(at 110.49 67.31 0)
			(effects
				(font
					(size 1.27 1.27)
				)
				(hide yes)
			)
		)
		(property "MPN" "CR0201-FX-0R00GLF"
			(at 130.81 46.99 0)
			(effects
				(font
					(size 1.27 1.27)
					(thickness 0.15)
				)
				(justify left bottom)
				(hide yes)
			)
		)
		(property "Manufacturer" "Bourns"
			(at 133.35 46.99 0)
			(effects
				(font
					(size 1.27 1.27)
					(thickness 0.15)
				)
				(justify left bottom)
				(hide yes)
			)
		)
		(property "License" "Apache-2.0"
			(at 135.89 46.99 0)
			(effects
				(font
					(size 1.27 1.27)
					(thickness 0.15)
				)
				(justify left bottom)
				(hide yes)
			)
		)
		(property "Author" "Antmicro"
			(at 138.43 46.99 0)
			(effects
				(font
					(size 1.27 1.27)
					(thickness 0.15)
				)
				(justify left bottom)
				(hide yes)
			)
		)
		(property "Val" "0R"
			(at 111.76 68.58 0)
			(effects
				(font
					(size 1.27 1.27)
					(thickness 0.15)
				)
			)
		)
		(property "Tolerance" "1%"
			(at 120.65 46.99 0)
			(effects
				(font
					(size 1.27 1.27)
				)
				(justify left bottom)
				(hide yes)
			)
		)
		(pin "1"
		)
		(pin "2"
		)
		(instances
			(project "com-express-7-baseboard"
				(path ""
					(reference "R284")
					(unit 1)
				)
				(path ""
					(reference "R250")
					(unit 1)
				)
			)
		)
	)
	(symbol
		(lib_id "antmicropower:GND")
		(at 223.52 250.19 0)
		(mirror y)
		(unit 1)
		(exclude_from_sim no)
		(in_bom yes)
		(on_board yes)
		(dnp no)
		(fields_autoplaced yes)
		(property "Reference" "#PWR0347"
			(at 223.52 256.54 0)
			(effects
				(font
					(size 1.27 1.27)
				)
				(justify left bottom)
				(hide yes)
			)
		)
		(property "Value" "GND"
			(at 223.52 255.27 0)
			(effects
				(font
					(size 1.27 1.27)
				)
			)
		)
		(property "Footprint" ""
			(at 223.52 250.19 0)
			(effects
				(font
					(size 1.27 1.27)
				)
				(justify left bottom)
				(hide yes)
			)
		)
		(property "Datasheet" ""
			(at 223.52 250.19 0)
			(effects
				(font
					(size 1.27 1.27)
				)
				(justify left bottom)
				(hide yes)
			)
		)
		(property "Description" ""
			(at 223.52 250.19 0)
			(effects
				(font
					(size 1.27 1.27)
				)
				(hide yes)
			)
		)
		(property "Author" "Antmicro"
			(at 214.63 257.81 0)
			(effects
				(font
					(size 1.27 1.27)
					(thickness 0.15)
				)
				(justify left bottom)
				(hide yes)
			)
		)
		(property "License" "Apache-2.0"
			(at 214.63 260.35 0)
			(effects
				(font
					(size 1.27 1.27)
					(thickness 0.15)
				)
				(justify left bottom)
				(hide yes)
			)
		)
		(pin "1"
		)
		(instances
			(project "com-express-7-baseboard"
				(path ""
					(reference "#PWR0398")
					(unit 1)
				)
				(path ""
					(reference "#PWR0347")
					(unit 1)
				)
			)
		)
	)
	(symbol
		(lib_id "antmicroTestPoints:TP_0.75mm_SMD")
		(at 149.86 200.66 0)
		(mirror y)
		(unit 1)
		(exclude_from_sim no)
		(in_bom no)
		(on_board yes)
		(dnp no)
		(fields_autoplaced yes)
		(property "Reference" "TP58"
			(at 144.78 200.66 0)
			(effects
				(font
					(size 1.27 1.27)
					(thickness 0.15)
				)
				(justify left)
			)
		)
		(property "Value" "TP_0.75mm_SMD"
			(at 139.065 204.47 0)
			(effects
				(font
					(size 1.27 1.27)
					(thickness 0.15)
				)
				(justify left bottom)
				(hide yes)
			)
		)
		(property "Footprint" "antmicro-footprints:TP_SMD_0.75mm"
			(at 139.065 207.01 0)
			(effects
				(font
					(size 1.27 1.27)
					(thickness 0.15)
				)
				(justify left bottom)
				(hide yes)
			)
		)
		(property "Datasheet" ""
			(at 132.08 213.36 0)
			(effects
				(font
					(size 1.27 1.27)
					(thickness 0.15)
				)
				(justify left bottom)
				(hide yes)
			)
		)
		(property "Description" ""
			(at 149.86 200.66 0)
			(effects
				(font
					(size 1.27 1.27)
				)
				(hide yes)
			)
		)
		(property "MPN" ""
			(at 139.065 212.09 0)
			(effects
				(font
					(size 1.27 1.27)
					(thickness 0.15)
				)
				(justify left bottom)
				(hide yes)
			)
		)
		(property "Manufacturer" ""
			(at 139.065 207.01 0)
			(effects
				(font
					(size 1.27 1.27)
					(thickness 0.15)
				)
				(justify left bottom)
				(hide yes)
			)
		)
		(property "Author" "Antmicro"
			(at 139.065 209.55 0)
			(effects
				(font
					(size 1.27 1.27)
					(thickness 0.15)
				)
				(justify left bottom)
				(hide yes)
			)
		)
		(property "License" "Apache-2.0"
			(at 139.065 212.09 0)
			(effects
				(font
					(size 1.27 1.27)
					(thickness 0.15)
				)
				(justify left bottom)
				(hide yes)
			)
		)
		(property "Public" "False"
			(at 139.7 214.63 0)
			(effects
				(font
					(size 1.27 1.27)
				)
				(justify left bottom)
				(hide yes)
			)
		)
		(pin "1"
		)
		(instances
			(project "com-express-7-baseboard"
				(path ""
					(reference "TP78")
					(unit 1)
				)
				(path ""
					(reference "TP58")
					(unit 1)
				)
			)
		)
	)
	(symbol
		(lib_id "antmicroCapacitors0402:C_100n_0402")
		(at 297.18 193.04 90)
		(unit 1)
		(exclude_from_sim no)
		(in_bom yes)
		(on_board yes)
		(dnp no)
		(fields_autoplaced yes)
		(property "Reference" "C166"
			(at 299.72 189.2236 90)
			(effects
				(font
					(size 1.27 1.27)
					(thickness 0.15)
				)
				(justify right)
			)
		)
		(property "Value" "C_100n_0402"
			(at 307.34 172.72 0)
			(effects
				(font
					(size 1.27 1.27)
					(thickness 0.15)
				)
				(justify left bottom)
				(hide yes)
			)
		)
		(property "Footprint" "antmicro-footprints:C_0402_1005Metric"
			(at 309.88 172.72 0)
			(effects
				(font
					(size 1.27 1.27)
					(thickness 0.15)
				)
				(justify left bottom)
				(hide yes)
			)
		)
		(property "Datasheet" "https://www.murata.com/products/productdetail?partno=GRM155R61H104KE14%23"
			(at 312.42 172.72 0)
			(effects
				(font
					(size 1.27 1.27)
					(thickness 0.15)
				)
				(justify left bottom)
				(hide yes)
			)
		)
		(property "Description" ""
			(at 297.18 193.04 0)
			(effects
				(font
					(size 1.27 1.27)
				)
				(hide yes)
			)
		)
		(property "MPN" "GRM155R61H104KE14D"
			(at 314.96 172.72 0)
			(effects
				(font
					(size 1.27 1.27)
					(thickness 0.15)
				)
				(justify left bottom)
				(hide yes)
			)
		)
		(property "Manufacturer" "Murata"
			(at 317.5 172.72 0)
			(effects
				(font
					(size 1.27 1.27)
					(thickness 0.15)
				)
				(justify left bottom)
				(hide yes)
			)
		)
		(property "License" "Apache-2.0"
			(at 320.04 172.72 0)
			(effects
				(font
					(size 1.27 1.27)
					(thickness 0.15)
				)
				(justify left bottom)
				(hide yes)
			)
		)
		(property "Author" "Antmicro"
			(at 322.58 172.72 0)
			(effects
				(font
					(size 1.27 1.27)
					(thickness 0.15)
				)
				(justify left bottom)
				(hide yes)
			)
		)
		(property "Val" "100n"
			(at 299.72 191.7636 90)
			(effects
				(font
					(size 1.27 1.27)
					(thickness 0.15)
				)
				(justify right)
			)
		)
		(property "Voltage" "50V"
			(at 325.12 172.72 0)
			(effects
				(font
					(size 1.27 1.27)
				)
				(justify left bottom)
				(hide yes)
			)
		)
		(property "Dielectric" "X5R"
			(at 327.66 172.72 0)
			(effects
				(font
					(size 1.27 1.27)
				)
				(justify left bottom)
				(hide yes)
			)
		)
		(property "Public" "False"
			(at 330.2 172.72 0)
			(effects
				(font
					(size 1.27 1.27)
				)
				(justify left bottom)
				(hide yes)
			)
		)
		(pin "2"
		)
		(pin "1"
		)
		(instances
			(project "com-express-7-baseboard"
				(path ""
					(reference "C193")
					(unit 1)
				)
				(path ""
					(reference "C166")
					(unit 1)
				)
			)
		)
	)
	(symbol
		(lib_id "antmicropower:+3V3")
		(at 74.93 210.82 0)
		(unit 1)
		(exclude_from_sim no)
		(in_bom yes)
		(on_board yes)
		(dnp no)
		(fields_autoplaced yes)
		(property "Reference" "#PWR0329"
			(at 90.17 210.82 0)
			(effects
				(font
					(size 1.27 1.27)
					(thickness 0.15)
				)
				(justify left bottom)
				(hide yes)
			)
		)
		(property "Value" "+3V3"
			(at 74.93 205.74 0)
			(effects
				(font
					(size 1.27 1.27)
					(thickness 0.15)
				)
			)
		)
		(property "Footprint" ""
			(at 90.17 218.44 0)
			(effects
				(font
					(size 1.27 1.27)
					(thickness 0.15)
				)
				(justify left bottom)
				(hide yes)
			)
		)
		(property "Datasheet" ""
			(at 90.17 220.98 0)
			(effects
				(font
					(size 1.27 1.27)
					(thickness 0.15)
				)
				(justify left bottom)
				(hide yes)
			)
		)
		(property "Description" ""
			(at 74.93 210.82 0)
			(effects
				(font
					(size 1.27 1.27)
				)
				(hide yes)
			)
		)
		(property "Author" "Antmicro"
			(at 90.17 213.36 0)
			(effects
				(font
					(size 1.27 1.27)
					(thickness 0.15)
				)
				(justify left bottom)
				(hide yes)
			)
		)
		(property "License" "Apache-2.0"
			(at 90.17 215.9 0)
			(effects
				(font
					(size 1.27 1.27)
					(thickness 0.15)
				)
				(justify left bottom)
				(hide yes)
			)
		)
		(pin "1"
		)
		(instances
			(project "com-express-7-baseboard"
				(path ""
					(reference "#PWR0380")
					(unit 1)
				)
				(path ""
					(reference "#PWR0329")
					(unit 1)
				)
			)
		)
	)
	(symbol
		(lib_id "antmicropower:+1V8")
		(at 125.73 208.28 0)
		(unit 1)
		(exclude_from_sim no)
		(in_bom yes)
		(on_board yes)
		(dnp no)
		(property "Reference" "#PWR0335"
			(at 140.97 210.82 0)
			(effects
				(font
					(size 1.27 1.27)
					(thickness 0.15)
				)
				(justify left bottom)
				(hide yes)
			)
		)
		(property "Value" "+1V8"
			(at 125.73 204.47 0)
			(effects
				(font
					(size 1.27 1.27)
					(thickness 0.15)
				)
			)
		)
		(property "Footprint" ""
			(at 140.97 215.9 0)
			(effects
				(font
					(size 1.27 1.27)
					(thickness 0.15)
				)
				(justify left bottom)
				(hide yes)
			)
		)
		(property "Datasheet" ""
			(at 140.97 218.44 0)
			(effects
				(font
					(size 1.27 1.27)
					(thickness 0.15)
				)
				(justify left bottom)
				(hide yes)
			)
		)
		(property "Description" ""
			(at 125.73 208.28 0)
			(effects
				(font
					(size 1.27 1.27)
				)
				(hide yes)
			)
		)
		(property "Author" "Antmicro"
			(at 140.97 213.36 0)
			(effects
				(font
					(size 1.27 1.27)
					(thickness 0.15)
				)
				(justify left bottom)
				(hide yes)
			)
		)
		(property "License" "Apache-2.0"
			(at 140.97 215.9 0)
			(effects
				(font
					(size 1.27 1.27)
					(thickness 0.15)
				)
				(justify left bottom)
				(hide yes)
			)
		)
		(pin "1"
		)
		(instances
			(project "com-express-7-baseboard"
				(path ""
					(reference "#PWR0386")
					(unit 1)
				)
				(path ""
					(reference "#PWR0335")
					(unit 1)
				)
			)
		)
	)
	(symbol
		(lib_id "antmicropower:+1V8")
		(at 193.04 218.44 0)
		(unit 1)
		(exclude_from_sim no)
		(in_bom yes)
		(on_board yes)
		(dnp no)
		(property "Reference" "#PWR0340"
			(at 208.28 220.98 0)
			(effects
				(font
					(size 1.27 1.27)
					(thickness 0.15)
				)
				(justify left bottom)
				(hide yes)
			)
		)
		(property "Value" "+1V8"
			(at 193.04 214.63 0)
			(effects
				(font
					(size 1.27 1.27)
					(thickness 0.15)
				)
			)
		)
		(property "Footprint" ""
			(at 208.28 226.06 0)
			(effects
				(font
					(size 1.27 1.27)
					(thickness 0.15)
				)
				(justify left bottom)
				(hide yes)
			)
		)
		(property "Datasheet" ""
			(at 208.28 228.6 0)
			(effects
				(font
					(size 1.27 1.27)
					(thickness 0.15)
				)
				(justify left bottom)
				(hide yes)
			)
		)
		(property "Description" ""
			(at 193.04 218.44 0)
			(effects
				(font
					(size 1.27 1.27)
				)
				(hide yes)
			)
		)
		(property "Author" "Antmicro"
			(at 208.28 223.52 0)
			(effects
				(font
					(size 1.27 1.27)
					(thickness 0.15)
				)
				(justify left bottom)
				(hide yes)
			)
		)
		(property "License" "Apache-2.0"
			(at 208.28 226.06 0)
			(effects
				(font
					(size 1.27 1.27)
					(thickness 0.15)
				)
				(justify left bottom)
				(hide yes)
			)
		)
		(pin "1"
		)
		(instances
			(project "com-express-7-baseboard"
				(path ""
					(reference "#PWR0391")
					(unit 1)
				)
				(path ""
					(reference "#PWR0340")
					(unit 1)
				)
			)
		)
	)
	(symbol
		(lib_id "antmicroResistorsmisc:R_0R_0201")
		(at 124.46 76.2 0)
		(unit 1)
		(exclude_from_sim no)
		(in_bom yes)
		(on_board yes)
		(dnp no)
		(property "Reference" "R256"
			(at 121.92 74.93 0)
			(effects
				(font
					(size 1.27 1.27)
					(thickness 0.15)
				)
			)
		)
		(property "Value" "R_0R_0201"
			(at 144.78 88.9 0)
			(effects
				(font
					(size 1.27 1.27)
					(thickness 0.15)
				)
				(justify left bottom)
				(hide yes)
			)
		)
		(property "Footprint" "antmicro-footprints:R_0201"
			(at 144.78 91.44 0)
			(effects
				(font
					(size 1.27 1.27)
					(thickness 0.15)
				)
				(justify left bottom)
				(hide yes)
			)
		)
		(property "Datasheet" "https://www.bourns.com/docs/product-datasheets/cr.pdf"
			(at 144.78 93.98 0)
			(effects
				(font
					(size 1.27 1.27)
					(thickness 0.15)
				)
				(justify left bottom)
				(hide yes)
			)
		)
		(property "Description" ""
			(at 124.46 76.2 0)
			(effects
				(font
					(size 1.27 1.27)
				)
				(hide yes)
			)
		)
		(property "MPN" "CR0201-FX-0R00GLF"
			(at 144.78 96.52 0)
			(effects
				(font
					(size 1.27 1.27)
					(thickness 0.15)
				)
				(justify left bottom)
				(hide yes)
			)
		)
		(property "Manufacturer" "Bourns"
			(at 144.78 99.06 0)
			(effects
				(font
					(size 1.27 1.27)
					(thickness 0.15)
				)
				(justify left bottom)
				(hide yes)
			)
		)
		(property "License" "Apache-2.0"
			(at 144.78 101.6 0)
			(effects
				(font
					(size 1.27 1.27)
					(thickness 0.15)
				)
				(justify left bottom)
				(hide yes)
			)
		)
		(property "Author" "Antmicro"
			(at 144.78 104.14 0)
			(effects
				(font
					(size 1.27 1.27)
					(thickness 0.15)
				)
				(justify left bottom)
				(hide yes)
			)
		)
		(property "Val" "0R"
			(at 130.81 74.93 0)
			(effects
				(font
					(size 1.27 1.27)
					(thickness 0.15)
				)
			)
		)
		(property "Tolerance" "1%"
			(at 144.78 86.36 0)
			(effects
				(font
					(size 1.27 1.27)
				)
				(justify left bottom)
				(hide yes)
			)
		)
		(pin "1"
		)
		(pin "2"
		)
		(instances
			(project "com-express-7-baseboard"
				(path ""
					(reference "R290")
					(unit 1)
				)
				(path ""
					(reference "R256")
					(unit 1)
				)
			)
		)
	)
	(symbol
		(lib_id "antmicroOscillators:Oscillator_156.25MHz_SG3225EEN")
		(at 80.01 190.5 0)
		(unit 1)
		(exclude_from_sim no)
		(in_bom yes)
		(on_board yes)
		(dnp no)
		(fields_autoplaced yes)
		(property "Reference" "Y2"
			(at 89.535 180.34 0)
			(effects
				(font
					(size 1.27 1.27)
					(thickness 0.15)
				)
			)
		)
		(property "Value" "Oscillator_156.25MHz_SG3225EEN"
			(at 100.33 210.82 0)
			(effects
				(font
					(size 1.27 1.27)
					(thickness 0.15)
				)
				(justify left bottom)
				(hide yes)
			)
		)
		(property "Footprint" "antmicro-footprints:Oscillator_SMD_Epson_SG3225EEN_3.2x2.5x1.2mm"
			(at 100.33 213.36 0)
			(effects
				(font
					(size 1.27 1.27)
					(thickness 0.15)
				)
				(justify left bottom)
				(hide yes)
			)
		)
		(property "Datasheet" "https://support.epson.biz/td/api/doc_check.php?dl=brief_SG3225EEN&lang=en"
			(at 100.33 215.9 0)
			(effects
				(font
					(size 1.27 1.27)
					(thickness 0.15)
				)
				(justify left bottom)
				(hide yes)
			)
		)
		(property "Description" ""
			(at 80.01 190.5 0)
			(effects
				(font
					(size 1.27 1.27)
				)
				(hide yes)
			)
		)
		(property "MPN" "SG3225EEN_156.250000M-CDGA3"
			(at 89.535 182.88 0)
			(effects
				(font
					(size 1.27 1.27)
					(thickness 0.15)
				)
			)
		)
		(property "Manufacturer" "Epson"
			(at 100.33 208.28 0)
			(effects
				(font
					(size 1.27 1.27)
					(thickness 0.15)
				)
				(justify left bottom)
				(hide yes)
			)
		)
		(property "Val" "156.25MHz"
			(at 89.535 185.42 0)
			(effects
				(font
					(size 1.27 1.27)
					(thickness 0.15)
				)
			)
		)
		(property "Author" "Antmicro"
			(at 100.33 218.44 0)
			(effects
				(font
					(size 1.27 1.27)
					(thickness 0.15)
				)
				(justify left bottom)
				(hide yes)
			)
		)
		(property "License" "Apache-2.0"
			(at 100.33 220.98 0)
			(effects
				(font
					(size 1.27 1.27)
					(thickness 0.15)
				)
				(justify left bottom)
				(hide yes)
			)
		)
		(property "Public" "False"
			(at 114.3 214.63 0)
			(effects
				(font
					(size 1.27 1.27)
				)
				(justify left bottom)
				(hide yes)
			)
		)
		(pin "4"
		)
		(pin "3"
		)
		(pin "6"
		)
		(pin "5"
		)
		(pin "2"
		)
		(pin "1"
		)
		(instances
			(project "com-express-7-baseboard"
				(path ""
					(reference "Y3")
					(unit 1)
				)
				(path ""
					(reference "Y2")
					(unit 1)
				)
			)
		)
	)
	(symbol
		(lib_id "antmicropower:GND")
		(at 327.66 215.9 0)
		(mirror y)
		(unit 1)
		(exclude_from_sim no)
		(in_bom yes)
		(on_board yes)
		(dnp no)
		(fields_autoplaced yes)
		(property "Reference" "#PWR0376"
			(at 327.66 222.25 0)
			(effects
				(font
					(size 1.27 1.27)
				)
				(justify left bottom)
				(hide yes)
			)
		)
		(property "Value" "GND"
			(at 327.66 220.98 0)
			(effects
				(font
					(size 1.27 1.27)
				)
			)
		)
		(property "Footprint" ""
			(at 327.66 215.9 0)
			(effects
				(font
					(size 1.27 1.27)
				)
				(justify left bottom)
				(hide yes)
			)
		)
		(property "Datasheet" ""
			(at 327.66 215.9 0)
			(effects
				(font
					(size 1.27 1.27)
				)
				(justify left bottom)
				(hide yes)
			)
		)
		(property "Description" ""
			(at 327.66 215.9 0)
			(effects
				(font
					(size 1.27 1.27)
				)
				(hide yes)
			)
		)
		(property "Author" "Antmicro"
			(at 318.77 223.52 0)
			(effects
				(font
					(size 1.27 1.27)
					(thickness 0.15)
				)
				(justify left bottom)
				(hide yes)
			)
		)
		(property "License" "Apache-2.0"
			(at 318.77 226.06 0)
			(effects
				(font
					(size 1.27 1.27)
					(thickness 0.15)
				)
				(justify left bottom)
				(hide yes)
			)
		)
		(pin "1"
		)
		(instances
			(project "com-express-7-baseboard"
				(path ""
					(reference "#PWR0427")
					(unit 1)
				)
				(path ""
					(reference "#PWR0376")
					(unit 1)
				)
			)
		)
	)
	(symbol
		(lib_id "antmicroResistors0402:R_10k_0402")
		(at 215.9 250.19 90)
		(unit 1)
		(exclude_from_sim no)
		(in_bom yes)
		(on_board yes)
		(dnp no)
		(property "Reference" "R266"
			(at 217.17 246.38 90)
			(effects
				(font
					(size 1.27 1.27)
					(thickness 0.15)
				)
				(justify right)
			)
		)
		(property "Value" "R_10k_0402"
			(at 228.6 229.87 0)
			(effects
				(font
					(size 1.27 1.27)
					(thickness 0.15)
				)
				(justify left bottom)
				(hide yes)
			)
		)
		(property "Footprint" "antmicro-footprints:R_0402_1005Metric"
			(at 231.14 229.87 0)
			(effects
				(font
					(size 1.27 1.27)
					(thickness 0.15)
				)
				(justify left bottom)
				(hide yes)
			)
		)
		(property "Datasheet" "https://www.bourns.com/docs/product-datasheets/cr.pdf"
			(at 233.68 229.87 0)
			(effects
				(font
					(size 1.27 1.27)
					(thickness 0.15)
				)
				(justify left bottom)
				(hide yes)
			)
		)
		(property "Description" ""
			(at 215.9 250.19 0)
			(effects
				(font
					(size 1.27 1.27)
				)
				(hide yes)
			)
		)
		(property "MPN" "CR0402-FX-1002GLF"
			(at 236.22 229.87 0)
			(effects
				(font
					(size 1.27 1.27)
					(thickness 0.15)
				)
				(justify left bottom)
				(hide yes)
			)
		)
		(property "Manufacturer" "Bourns"
			(at 238.76 229.87 0)
			(effects
				(font
					(size 1.27 1.27)
					(thickness 0.15)
				)
				(justify left bottom)
				(hide yes)
			)
		)
		(property "License" "Apache-2.0"
			(at 241.3 229.87 0)
			(effects
				(font
					(size 1.27 1.27)
					(thickness 0.15)
				)
				(justify left bottom)
				(hide yes)
			)
		)
		(property "Author" "Antmicro"
			(at 243.84 229.87 0)
			(effects
				(font
					(size 1.27 1.27)
					(thickness 0.15)
				)
				(justify left bottom)
				(hide yes)
			)
		)
		(property "Val" "10k"
			(at 217.17 248.92 90)
			(effects
				(font
					(size 1.27 1.27)
					(thickness 0.15)
				)
				(justify right)
			)
		)
		(property "Tolerance" "1%"
			(at 226.06 229.87 0)
			(effects
				(font
					(size 1.27 1.27)
				)
				(justify left bottom)
				(hide yes)
			)
		)
		(property "Public" "False"
			(at 246.38 229.87 0)
			(effects
				(font
					(size 1.27 1.27)
				)
				(justify left bottom)
				(hide yes)
			)
		)
		(pin "2"
		)
		(pin "1"
		)
		(instances
			(project "com-express-7-baseboard"
				(path ""
					(reference "R300")
					(unit 1)
				)
				(path ""
					(reference "R266")
					(unit 1)
				)
			)
		)
	)
	(symbol
		(lib_id "antmicroResistorsmisc:R_0R_0201")
		(at 287.02 78.74 0)
		(unit 1)
		(exclude_from_sim no)
		(in_bom yes)
		(on_board yes)
		(dnp no)
		(property "Reference" "R274"
			(at 284.48 80.01 0)
			(effects
				(font
					(size 1.27 1.27)
					(thickness 0.15)
				)
			)
		)
		(property "Value" "R_0R_0201"
			(at 307.34 91.44 0)
			(effects
				(font
					(size 1.27 1.27)
					(thickness 0.15)
				)
				(justify left bottom)
				(hide yes)
			)
		)
		(property "Footprint" "antmicro-footprints:R_0201"
			(at 307.34 93.98 0)
			(effects
				(font
					(size 1.27 1.27)
					(thickness 0.15)
				)
				(justify left bottom)
				(hide yes)
			)
		)
		(property "Datasheet" "https://www.bourns.com/docs/product-datasheets/cr.pdf"
			(at 307.34 96.52 0)
			(effects
				(font
					(size 1.27 1.27)
					(thickness 0.15)
				)
				(justify left bottom)
				(hide yes)
			)
		)
		(property "Description" ""
			(at 287.02 78.74 0)
			(effects
				(font
					(size 1.27 1.27)
				)
				(hide yes)
			)
		)
		(property "MPN" "CR0201-FX-0R00GLF"
			(at 307.34 99.06 0)
			(effects
				(font
					(size 1.27 1.27)
					(thickness 0.15)
				)
				(justify left bottom)
				(hide yes)
			)
		)
		(property "Manufacturer" "Bourns"
			(at 307.34 101.6 0)
			(effects
				(font
					(size 1.27 1.27)
					(thickness 0.15)
				)
				(justify left bottom)
				(hide yes)
			)
		)
		(property "License" "Apache-2.0"
			(at 307.34 104.14 0)
			(effects
				(font
					(size 1.27 1.27)
					(thickness 0.15)
				)
				(justify left bottom)
				(hide yes)
			)
		)
		(property "Author" "Antmicro"
			(at 307.34 106.68 0)
			(effects
				(font
					(size 1.27 1.27)
					(thickness 0.15)
				)
				(justify left bottom)
				(hide yes)
			)
		)
		(property "Val" "0R"
			(at 293.37 80.01 0)
			(effects
				(font
					(size 1.27 1.27)
					(thickness 0.15)
				)
			)
		)
		(property "Tolerance" "1%"
			(at 307.34 88.9 0)
			(effects
				(font
					(size 1.27 1.27)
				)
				(justify left bottom)
				(hide yes)
			)
		)
		(pin "1"
		)
		(pin "2"
		)
		(instances
			(project "com-express-7-baseboard"
				(path ""
					(reference "R308")
					(unit 1)
				)
				(path ""
					(reference "R274")
					(unit 1)
				)
			)
		)
	)
	(symbol
		(lib_id "antmicroCapacitors0402:C_100n_0402")
		(at 105.41 218.44 90)
		(unit 1)
		(exclude_from_sim no)
		(in_bom yes)
		(on_board yes)
		(dnp no)
		(fields_autoplaced yes)
		(property "Reference" "C150"
			(at 107.95 214.6235 90)
			(effects
				(font
					(size 1.27 1.27)
				)
				(justify right)
			)
		)
		(property "Value" "C_100n_0402"
			(at 109.22 218.44 0)
			(effects
				(font
					(size 1.27 1.27)
				)
				(justify left bottom)
				(hide yes)
			)
		)
		(property "Footprint" "antmicro-footprints:C_0402_1005Metric"
			(at 100.33 213.36 0)
			(effects
				(font
					(size 1.524 1.524)
				)
				(justify left bottom)
				(hide yes)
			)
		)
		(property "Datasheet" "https://www.murata.com/products/productdetail?partno=GRM155R61H104KE14%23"
			(at 105.41 218.44 0)
			(effects
				(font
					(size 1.27 1.27)
				)
				(justify left bottom)
				(hide yes)
			)
		)
		(property "Description" ""
			(at 105.41 218.44 0)
			(effects
				(font
					(size 1.27 1.27)
				)
				(hide yes)
			)
		)
		(property "Manufacturer" "Murata"
			(at 95.25 213.36 0)
			(effects
				(font
					(size 1.524 1.524)
				)
				(justify left bottom)
				(hide yes)
			)
		)
		(property "MPN" "GRM155R61H104KE14D"
			(at 97.79 213.36 0)
			(effects
				(font
					(size 1.524 1.524)
				)
				(justify left bottom)
				(hide yes)
			)
		)
		(property "Val" "100n"
			(at 107.95 217.1635 90)
			(effects
				(font
					(size 1.27 1.27)
				)
				(justify right)
			)
		)
		(property "License" "Apache-2.0"
			(at 128.27 198.12 0)
			(effects
				(font
					(size 1.27 1.27)
					(thickness 0.15)
				)
				(justify left bottom)
				(hide yes)
			)
		)
		(property "Author" "Antmicro"
			(at 130.81 198.12 0)
			(effects
				(font
					(size 1.27 1.27)
					(thickness 0.15)
				)
				(justify left bottom)
				(hide yes)
			)
		)
		(property "Voltage" "50V"
			(at 133.35 198.12 0)
			(effects
				(font
					(size 1.27 1.27)
				)
				(justify left bottom)
				(hide yes)
			)
		)
		(property "Dielectric" "X5R"
			(at 135.89 198.12 0)
			(effects
				(font
					(size 1.27 1.27)
				)
				(justify left bottom)
				(hide yes)
			)
		)
		(property "Public" "False"
			(at 138.43 198.12 0)
			(effects
				(font
					(size 1.27 1.27)
				)
				(justify left bottom)
				(hide yes)
			)
		)
		(pin "1"
		)
		(pin "2"
		)
		(instances
			(project "com-express-7-baseboard"
				(path ""
					(reference "C177")
					(unit 1)
				)
				(path ""
					(reference "C150")
					(unit 1)
				)
			)
		)
	)
	(symbol
		(lib_id "antmicropower:GND")
		(at 78.74 234.95 0)
		(mirror y)
		(unit 1)
		(exclude_from_sim no)
		(in_bom yes)
		(on_board yes)
		(dnp no)
		(fields_autoplaced yes)
		(property "Reference" "#PWR0332"
			(at 78.74 241.3 0)
			(effects
				(font
					(size 1.27 1.27)
				)
				(justify left bottom)
				(hide yes)
			)
		)
		(property "Value" "GND"
			(at 78.74 240.03 0)
			(effects
				(font
					(size 1.27 1.27)
				)
			)
		)
		(property "Footprint" ""
			(at 78.74 234.95 0)
			(effects
				(font
					(size 1.27 1.27)
				)
				(justify left bottom)
				(hide yes)
			)
		)
		(property "Datasheet" ""
			(at 78.74 234.95 0)
			(effects
				(font
					(size 1.27 1.27)
				)
				(justify left bottom)
				(hide yes)
			)
		)
		(property "Description" ""
			(at 78.74 234.95 0)
			(effects
				(font
					(size 1.27 1.27)
				)
				(hide yes)
			)
		)
		(property "Author" "Antmicro"
			(at 69.85 242.57 0)
			(effects
				(font
					(size 1.27 1.27)
					(thickness 0.15)
				)
				(justify left bottom)
				(hide yes)
			)
		)
		(property "License" "Apache-2.0"
			(at 69.85 245.11 0)
			(effects
				(font
					(size 1.27 1.27)
					(thickness 0.15)
				)
				(justify left bottom)
				(hide yes)
			)
		)
		(pin "1"
		)
		(instances
			(project "com-express-7-baseboard"
				(path ""
					(reference "#PWR0383")
					(unit 1)
				)
				(path ""
					(reference "#PWR0332")
					(unit 1)
				)
			)
		)
	)
	(symbol
		(lib_id "antmicroResistorsmisc:R_0R_0201")
		(at 307.34 71.12 90)
		(unit 1)
		(exclude_from_sim no)
		(in_bom yes)
		(on_board yes)
		(dnp yes)
		(property "Reference" "R277"
			(at 308.61 63.5 0)
			(effects
				(font
					(size 1.27 1.27)
					(thickness 0.15)
				)
			)
		)
		(property "Value" "R_0R_0201"
			(at 320.04 50.8 0)
			(effects
				(font
					(size 1.27 1.27)
					(thickness 0.15)
				)
				(justify left bottom)
				(hide yes)
			)
		)
		(property "Footprint" "antmicro-footprints:R_0201"
			(at 322.58 50.8 0)
			(effects
				(font
					(size 1.27 1.27)
					(thickness 0.15)
				)
				(justify left bottom)
				(hide yes)
			)
		)
		(property "Datasheet" "https://www.bourns.com/docs/product-datasheets/cr.pdf"
			(at 325.12 50.8 0)
			(effects
				(font
					(size 1.27 1.27)
					(thickness 0.15)
				)
				(justify left bottom)
				(hide yes)
			)
		)
		(property "Description" ""
			(at 307.34 71.12 0)
			(effects
				(font
					(size 1.27 1.27)
				)
				(hide yes)
			)
		)
		(property "MPN" "CR0201-FX-0R00GLF"
			(at 327.66 50.8 0)
			(effects
				(font
					(size 1.27 1.27)
					(thickness 0.15)
				)
				(justify left bottom)
				(hide yes)
			)
		)
		(property "Manufacturer" "Bourns"
			(at 330.2 50.8 0)
			(effects
				(font
					(size 1.27 1.27)
					(thickness 0.15)
				)
				(justify left bottom)
				(hide yes)
			)
		)
		(property "License" "Apache-2.0"
			(at 332.74 50.8 0)
			(effects
				(font
					(size 1.27 1.27)
					(thickness 0.15)
				)
				(justify left bottom)
				(hide yes)
			)
		)
		(property "Author" "Antmicro"
			(at 335.28 50.8 0)
			(effects
				(font
					(size 1.27 1.27)
					(thickness 0.15)
				)
				(justify left bottom)
				(hide yes)
			)
		)
		(property "Val" "0R"
			(at 308.61 72.39 0)
			(effects
				(font
					(size 1.27 1.27)
					(thickness 0.15)
				)
			)
		)
		(property "Tolerance" "1%"
			(at 317.5 50.8 0)
			(effects
				(font
					(size 1.27 1.27)
				)
				(justify left bottom)
				(hide yes)
			)
		)
		(pin "1"
		)
		(pin "2"
		)
		(instances
			(project "com-express-7-baseboard"
				(path ""
					(reference "R311")
					(unit 1)
				)
				(path ""
					(reference "R277")
					(unit 1)
				)
			)
		)
	)
	(symbol
		(lib_id "antmicroTestPoints:TP_0.75mm_SMD")
		(at 149.86 208.28 0)
		(mirror y)
		(unit 1)
		(exclude_from_sim no)
		(in_bom no)
		(on_board yes)
		(dnp no)
		(fields_autoplaced yes)
		(property "Reference" "TP60"
			(at 144.78 208.28 0)
			(effects
				(font
					(size 1.27 1.27)
					(thickness 0.15)
				)
				(justify left)
			)
		)
		(property "Value" "TP_0.75mm_SMD"
			(at 139.065 212.09 0)
			(effects
				(font
					(size 1.27 1.27)
					(thickness 0.15)
				)
				(justify left bottom)
				(hide yes)
			)
		)
		(property "Footprint" "antmicro-footprints:TP_SMD_0.75mm"
			(at 139.065 214.63 0)
			(effects
				(font
					(size 1.27 1.27)
					(thickness 0.15)
				)
				(justify left bottom)
				(hide yes)
			)
		)
		(property "Datasheet" ""
			(at 132.08 220.98 0)
			(effects
				(font
					(size 1.27 1.27)
					(thickness 0.15)
				)
				(justify left bottom)
				(hide yes)
			)
		)
		(property "Description" ""
			(at 149.86 208.28 0)
			(effects
				(font
					(size 1.27 1.27)
				)
				(hide yes)
			)
		)
		(property "MPN" ""
			(at 139.065 219.71 0)
			(effects
				(font
					(size 1.27 1.27)
					(thickness 0.15)
				)
				(justify left bottom)
				(hide yes)
			)
		)
		(property "Manufacturer" ""
			(at 139.065 214.63 0)
			(effects
				(font
					(size 1.27 1.27)
					(thickness 0.15)
				)
				(justify left bottom)
				(hide yes)
			)
		)
		(property "Author" "Antmicro"
			(at 139.065 217.17 0)
			(effects
				(font
					(size 1.27 1.27)
					(thickness 0.15)
				)
				(justify left bottom)
				(hide yes)
			)
		)
		(property "License" "Apache-2.0"
			(at 139.065 219.71 0)
			(effects
				(font
					(size 1.27 1.27)
					(thickness 0.15)
				)
				(justify left bottom)
				(hide yes)
			)
		)
		(property "Public" "False"
			(at 139.7 222.25 0)
			(effects
				(font
					(size 1.27 1.27)
				)
				(justify left bottom)
				(hide yes)
			)
		)
		(pin "1"
		)
		(instances
			(project "com-express-7-baseboard"
				(path ""
					(reference "TP80")
					(unit 1)
				)
				(path ""
					(reference "TP60")
					(unit 1)
				)
			)
		)
	)
	(symbol
		(lib_id "antmicroResistors0402:R_10k_0402")
		(at 223.52 250.19 90)
		(unit 1)
		(exclude_from_sim no)
		(in_bom yes)
		(on_board yes)
		(dnp no)
		(property "Reference" "R268"
			(at 224.79 246.38 90)
			(effects
				(font
					(size 1.27 1.27)
					(thickness 0.15)
				)
				(justify right)
			)
		)
		(property "Value" "R_10k_0402"
			(at 236.22 229.87 0)
			(effects
				(font
					(size 1.27 1.27)
					(thickness 0.15)
				)
				(justify left bottom)
				(hide yes)
			)
		)
		(property "Footprint" "antmicro-footprints:R_0402_1005Metric"
			(at 238.76 229.87 0)
			(effects
				(font
					(size 1.27 1.27)
					(thickness 0.15)
				)
				(justify left bottom)
				(hide yes)
			)
		)
		(property "Datasheet" "https://www.bourns.com/docs/product-datasheets/cr.pdf"
			(at 241.3 229.87 0)
			(effects
				(font
					(size 1.27 1.27)
					(thickness 0.15)
				)
				(justify left bottom)
				(hide yes)
			)
		)
		(property "Description" ""
			(at 223.52 250.19 0)
			(effects
				(font
					(size 1.27 1.27)
				)
				(hide yes)
			)
		)
		(property "MPN" "CR0402-FX-1002GLF"
			(at 243.84 229.87 0)
			(effects
				(font
					(size 1.27 1.27)
					(thickness 0.15)
				)
				(justify left bottom)
				(hide yes)
			)
		)
		(property "Manufacturer" "Bourns"
			(at 246.38 229.87 0)
			(effects
				(font
					(size 1.27 1.27)
					(thickness 0.15)
				)
				(justify left bottom)
				(hide yes)
			)
		)
		(property "License" "Apache-2.0"
			(at 248.92 229.87 0)
			(effects
				(font
					(size 1.27 1.27)
					(thickness 0.15)
				)
				(justify left bottom)
				(hide yes)
			)
		)
		(property "Author" "Antmicro"
			(at 251.46 229.87 0)
			(effects
				(font
					(size 1.27 1.27)
					(thickness 0.15)
				)
				(justify left bottom)
				(hide yes)
			)
		)
		(property "Val" "10k"
			(at 224.79 248.92 90)
			(effects
				(font
					(size 1.27 1.27)
					(thickness 0.15)
				)
				(justify right)
			)
		)
		(property "Tolerance" "1%"
			(at 233.68 229.87 0)
			(effects
				(font
					(size 1.27 1.27)
				)
				(justify left bottom)
				(hide yes)
			)
		)
		(property "Public" "False"
			(at 254 229.87 0)
			(effects
				(font
					(size 1.27 1.27)
				)
				(justify left bottom)
				(hide yes)
			)
		)
		(pin "2"
		)
		(pin "1"
		)
		(instances
			(project "com-express-7-baseboard"
				(path ""
					(reference "R302")
					(unit 1)
				)
				(path ""
					(reference "R268")
					(unit 1)
				)
			)
		)
	)
	(symbol
		(lib_id "antmicroCapacitors0402:C_100n_0402")
		(at 307.34 215.9 90)
		(unit 1)
		(exclude_from_sim no)
		(in_bom yes)
		(on_board yes)
		(dnp no)
		(fields_autoplaced yes)
		(property "Reference" "C170"
			(at 309.88 212.0836 90)
			(effects
				(font
					(size 1.27 1.27)
					(thickness 0.15)
				)
				(justify right)
			)
		)
		(property "Value" "C_100n_0402"
			(at 317.5 195.58 0)
			(effects
				(font
					(size 1.27 1.27)
					(thickness 0.15)
				)
				(justify left bottom)
				(hide yes)
			)
		)
		(property "Footprint" "antmicro-footprints:C_0402_1005Metric"
			(at 320.04 195.58 0)
			(effects
				(font
					(size 1.27 1.27)
					(thickness 0.15)
				)
				(justify left bottom)
				(hide yes)
			)
		)
		(property "Datasheet" "https://www.murata.com/products/productdetail?partno=GRM155R61H104KE14%23"
			(at 322.58 195.58 0)
			(effects
				(font
					(size 1.27 1.27)
					(thickness 0.15)
				)
				(justify left bottom)
				(hide yes)
			)
		)
		(property "Description" ""
			(at 307.34 215.9 0)
			(effects
				(font
					(size 1.27 1.27)
				)
				(hide yes)
			)
		)
		(property "MPN" "GRM155R61H104KE14D"
			(at 325.12 195.58 0)
			(effects
				(font
					(size 1.27 1.27)
					(thickness 0.15)
				)
				(justify left bottom)
				(hide yes)
			)
		)
		(property "Manufacturer" "Murata"
			(at 327.66 195.58 0)
			(effects
				(font
					(size 1.27 1.27)
					(thickness 0.15)
				)
				(justify left bottom)
				(hide yes)
			)
		)
		(property "License" "Apache-2.0"
			(at 330.2 195.58 0)
			(effects
				(font
					(size 1.27 1.27)
					(thickness 0.15)
				)
				(justify left bottom)
				(hide yes)
			)
		)
		(property "Author" "Antmicro"
			(at 332.74 195.58 0)
			(effects
				(font
					(size 1.27 1.27)
					(thickness 0.15)
				)
				(justify left bottom)
				(hide yes)
			)
		)
		(property "Val" "100n"
			(at 309.88 214.6236 90)
			(effects
				(font
					(size 1.27 1.27)
					(thickness 0.15)
				)
				(justify right)
			)
		)
		(property "Voltage" "50V"
			(at 335.28 195.58 0)
			(effects
				(font
					(size 1.27 1.27)
				)
				(justify left bottom)
				(hide yes)
			)
		)
		(property "Dielectric" "X5R"
			(at 337.82 195.58 0)
			(effects
				(font
					(size 1.27 1.27)
				)
				(justify left bottom)
				(hide yes)
			)
		)
		(property "Public" "False"
			(at 340.36 195.58 0)
			(effects
				(font
					(size 1.27 1.27)
				)
				(justify left bottom)
				(hide yes)
			)
		)
		(pin "2"
		)
		(pin "1"
		)
		(instances
			(project "com-express-7-baseboard"
				(path ""
					(reference "C197")
					(unit 1)
				)
				(path ""
					(reference "C170")
					(unit 1)
				)
			)
		)
	)
	(symbol
		(lib_id "antmicropower:GND")
		(at 307.34 215.9 0)
		(mirror y)
		(unit 1)
		(exclude_from_sim no)
		(in_bom yes)
		(on_board yes)
		(dnp no)
		(fields_autoplaced yes)
		(property "Reference" "#PWR0372"
			(at 307.34 222.25 0)
			(effects
				(font
					(size 1.27 1.27)
				)
				(justify left bottom)
				(hide yes)
			)
		)
		(property "Value" "GND"
			(at 307.34 220.98 0)
			(effects
				(font
					(size 1.27 1.27)
				)
			)
		)
		(property "Footprint" ""
			(at 307.34 215.9 0)
			(effects
				(font
					(size 1.27 1.27)
				)
				(justify left bottom)
				(hide yes)
			)
		)
		(property "Datasheet" ""
			(at 307.34 215.9 0)
			(effects
				(font
					(size 1.27 1.27)
				)
				(justify left bottom)
				(hide yes)
			)
		)
		(property "Description" ""
			(at 307.34 215.9 0)
			(effects
				(font
					(size 1.27 1.27)
				)
				(hide yes)
			)
		)
		(property "Author" "Antmicro"
			(at 298.45 223.52 0)
			(effects
				(font
					(size 1.27 1.27)
					(thickness 0.15)
				)
				(justify left bottom)
				(hide yes)
			)
		)
		(property "License" "Apache-2.0"
			(at 298.45 226.06 0)
			(effects
				(font
					(size 1.27 1.27)
					(thickness 0.15)
				)
				(justify left bottom)
				(hide yes)
			)
		)
		(pin "1"
		)
		(instances
			(project "com-express-7-baseboard"
				(path ""
					(reference "#PWR0423")
					(unit 1)
				)
				(path ""
					(reference "#PWR0372")
					(unit 1)
				)
			)
		)
	)
	(symbol
		(lib_id "antmicroTestPoints:TP_0.75mm_SMD")
		(at 194.31 190.5 0)
		(unit 1)
		(exclude_from_sim no)
		(in_bom no)
		(on_board yes)
		(dnp no)
		(fields_autoplaced yes)
		(property "Reference" "TP67"
			(at 199.39 190.5 0)
			(effects
				(font
					(size 1.27 1.27)
					(thickness 0.15)
				)
				(justify left)
			)
		)
		(property "Value" "TP_0.75mm_SMD"
			(at 205.105 194.31 0)
			(effects
				(font
					(size 1.27 1.27)
					(thickness 0.15)
				)
				(justify left bottom)
				(hide yes)
			)
		)
		(property "Footprint" "antmicro-footprints:TP_SMD_0.75mm"
			(at 205.105 196.85 0)
			(effects
				(font
					(size 1.27 1.27)
					(thickness 0.15)
				)
				(justify left bottom)
				(hide yes)
			)
		)
		(property "Datasheet" ""
			(at 212.09 203.2 0)
			(effects
				(font
					(size 1.27 1.27)
					(thickness 0.15)
				)
				(justify left bottom)
				(hide yes)
			)
		)
		(property "Description" ""
			(at 194.31 190.5 0)
			(effects
				(font
					(size 1.27 1.27)
				)
				(hide yes)
			)
		)
		(property "MPN" ""
			(at 205.105 201.93 0)
			(effects
				(font
					(size 1.27 1.27)
					(thickness 0.15)
				)
				(justify left bottom)
				(hide yes)
			)
		)
		(property "Manufacturer" ""
			(at 205.105 196.85 0)
			(effects
				(font
					(size 1.27 1.27)
					(thickness 0.15)
				)
				(justify left bottom)
				(hide yes)
			)
		)
		(property "Author" "Antmicro"
			(at 205.105 199.39 0)
			(effects
				(font
					(size 1.27 1.27)
					(thickness 0.15)
				)
				(justify left bottom)
				(hide yes)
			)
		)
		(property "License" "Apache-2.0"
			(at 205.105 201.93 0)
			(effects
				(font
					(size 1.27 1.27)
					(thickness 0.15)
				)
				(justify left bottom)
				(hide yes)
			)
		)
		(property "Public" "False"
			(at 204.47 204.47 0)
			(effects
				(font
					(size 1.27 1.27)
				)
				(justify left bottom)
				(hide yes)
			)
		)
		(pin "1"
		)
		(instances
			(project "com-express-7-baseboard"
				(path ""
					(reference "TP87")
					(unit 1)
				)
				(path ""
					(reference "TP67")
					(unit 1)
				)
			)
		)
	)
	(symbol
		(lib_id "antmicroResistors0402:R_10k_0402")
		(at 209.55 121.92 90)
		(unit 1)
		(exclude_from_sim no)
		(in_bom yes)
		(on_board yes)
		(dnp no)
		(fields_autoplaced yes)
		(property "Reference" "R267"
			(at 212.09 118.11 90)
			(effects
				(font
					(size 1.27 1.27)
					(thickness 0.15)
				)
				(justify right)
			)
		)
		(property "Value" "R_10k_0402"
			(at 222.25 101.6 0)
			(effects
				(font
					(size 1.27 1.27)
					(thickness 0.15)
				)
				(justify left bottom)
				(hide yes)
			)
		)
		(property "Footprint" "antmicro-footprints:R_0402_1005Metric"
			(at 224.79 101.6 0)
			(effects
				(font
					(size 1.27 1.27)
					(thickness 0.15)
				)
				(justify left bottom)
				(hide yes)
			)
		)
		(property "Datasheet" "https://www.bourns.com/docs/product-datasheets/cr.pdf"
			(at 227.33 101.6 0)
			(effects
				(font
					(size 1.27 1.27)
					(thickness 0.15)
				)
				(justify left bottom)
				(hide yes)
			)
		)
		(property "Description" ""
			(at 209.55 121.92 0)
			(effects
				(font
					(size 1.27 1.27)
				)
				(hide yes)
			)
		)
		(property "MPN" "CR0402-FX-1002GLF"
			(at 229.87 101.6 0)
			(effects
				(font
					(size 1.27 1.27)
					(thickness 0.15)
				)
				(justify left bottom)
				(hide yes)
			)
		)
		(property "Manufacturer" "Bourns"
			(at 232.41 101.6 0)
			(effects
				(font
					(size 1.27 1.27)
					(thickness 0.15)
				)
				(justify left bottom)
				(hide yes)
			)
		)
		(property "License" "Apache-2.0"
			(at 234.95 101.6 0)
			(effects
				(font
					(size 1.27 1.27)
					(thickness 0.15)
				)
				(justify left bottom)
				(hide yes)
			)
		)
		(property "Author" "Antmicro"
			(at 237.49 101.6 0)
			(effects
				(font
					(size 1.27 1.27)
					(thickness 0.15)
				)
				(justify left bottom)
				(hide yes)
			)
		)
		(property "Val" "10k"
			(at 212.09 120.65 90)
			(effects
				(font
					(size 1.27 1.27)
					(thickness 0.15)
				)
				(justify right)
			)
		)
		(property "Tolerance" "1%"
			(at 219.71 101.6 0)
			(effects
				(font
					(size 1.27 1.27)
				)
				(justify left bottom)
				(hide yes)
			)
		)
		(property "Public" "False"
			(at 240.03 101.6 0)
			(effects
				(font
					(size 1.27 1.27)
				)
				(justify left bottom)
				(hide yes)
			)
		)
		(pin "2"
		)
		(pin "1"
		)
		(instances
			(project "com-express-7-baseboard"
				(path ""
					(reference "R301")
					(unit 1)
				)
				(path ""
					(reference "R267")
					(unit 1)
				)
			)
		)
	)
	(symbol
		(lib_id "antmicroResistorsmisc:R_0R_0201")
		(at 118.11 67.31 90)
		(unit 1)
		(exclude_from_sim no)
		(in_bom yes)
		(on_board yes)
		(dnp yes)
		(property "Reference" "R254"
			(at 119.38 59.69 0)
			(effects
				(font
					(size 1.27 1.27)
					(thickness 0.15)
				)
			)
		)
		(property "Value" "R_0R_0201"
			(at 130.81 46.99 0)
			(effects
				(font
					(size 1.27 1.27)
					(thickness 0.15)
				)
				(justify left bottom)
				(hide yes)
			)
		)
		(property "Footprint" "antmicro-footprints:R_0201"
			(at 133.35 46.99 0)
			(effects
				(font
					(size 1.27 1.27)
					(thickness 0.15)
				)
				(justify left bottom)
				(hide yes)
			)
		)
		(property "Datasheet" "https://www.bourns.com/docs/product-datasheets/cr.pdf"
			(at 135.89 46.99 0)
			(effects
				(font
					(size 1.27 1.27)
					(thickness 0.15)
				)
				(justify left bottom)
				(hide yes)
			)
		)
		(property "Description" ""
			(at 118.11 67.31 0)
			(effects
				(font
					(size 1.27 1.27)
				)
				(hide yes)
			)
		)
		(property "MPN" "CR0201-FX-0R00GLF"
			(at 138.43 46.99 0)
			(effects
				(font
					(size 1.27 1.27)
					(thickness 0.15)
				)
				(justify left bottom)
				(hide yes)
			)
		)
		(property "Manufacturer" "Bourns"
			(at 140.97 46.99 0)
			(effects
				(font
					(size 1.27 1.27)
					(thickness 0.15)
				)
				(justify left bottom)
				(hide yes)
			)
		)
		(property "License" "Apache-2.0"
			(at 143.51 46.99 0)
			(effects
				(font
					(size 1.27 1.27)
					(thickness 0.15)
				)
				(justify left bottom)
				(hide yes)
			)
		)
		(property "Author" "Antmicro"
			(at 146.05 46.99 0)
			(effects
				(font
					(size 1.27 1.27)
					(thickness 0.15)
				)
				(justify left bottom)
				(hide yes)
			)
		)
		(property "Val" "0R"
			(at 119.38 68.58 0)
			(effects
				(font
					(size 1.27 1.27)
					(thickness 0.15)
				)
			)
		)
		(property "Tolerance" "1%"
			(at 128.27 46.99 0)
			(effects
				(font
					(size 1.27 1.27)
				)
				(justify left bottom)
				(hide yes)
			)
		)
		(pin "1"
		)
		(pin "2"
		)
		(instances
			(project "com-express-7-baseboard"
				(path ""
					(reference "R288")
					(unit 1)
				)
				(path ""
					(reference "R254")
					(unit 1)
				)
			)
		)
	)
	(symbol
		(lib_id "antmicropower:GND")
		(at 261.62 208.28 0)
		(mirror y)
		(unit 1)
		(exclude_from_sim no)
		(in_bom yes)
		(on_board yes)
		(dnp no)
		(fields_autoplaced yes)
		(property "Reference" "#PWR0354"
			(at 261.62 214.63 0)
			(effects
				(font
					(size 1.27 1.27)
				)
				(justify left bottom)
				(hide yes)
			)
		)
		(property "Value" "GND"
			(at 261.62 213.36 0)
			(effects
				(font
					(size 1.27 1.27)
				)
			)
		)
		(property "Footprint" ""
			(at 261.62 208.28 0)
			(effects
				(font
					(size 1.27 1.27)
				)
				(justify left bottom)
				(hide yes)
			)
		)
		(property "Datasheet" ""
			(at 261.62 208.28 0)
			(effects
				(font
					(size 1.27 1.27)
				)
				(justify left bottom)
				(hide yes)
			)
		)
		(property "Description" ""
			(at 261.62 208.28 0)
			(effects
				(font
					(size 1.27 1.27)
				)
				(hide yes)
			)
		)
		(property "Author" "Antmicro"
			(at 252.73 215.9 0)
			(effects
				(font
					(size 1.27 1.27)
					(thickness 0.15)
				)
				(justify left bottom)
				(hide yes)
			)
		)
		(property "License" "Apache-2.0"
			(at 252.73 218.44 0)
			(effects
				(font
					(size 1.27 1.27)
					(thickness 0.15)
				)
				(justify left bottom)
				(hide yes)
			)
		)
		(pin "1"
		)
		(instances
			(project "com-express-7-baseboard"
				(path ""
					(reference "#PWR0405")
					(unit 1)
				)
				(path ""
					(reference "#PWR0354")
					(unit 1)
				)
			)
		)
	)
	(symbol
		(lib_id "antmicropower:GND")
		(at 327.66 170.18 0)
		(mirror y)
		(unit 1)
		(exclude_from_sim no)
		(in_bom yes)
		(on_board yes)
		(dnp no)
		(property "Reference" "#PWR0375"
			(at 327.66 176.53 0)
			(effects
				(font
					(size 1.27 1.27)
				)
				(justify left bottom)
				(hide yes)
			)
		)
		(property "Value" "GND"
			(at 327.66 175.26 0)
			(effects
				(font
					(size 1.27 1.27)
				)
			)
		)
		(property "Footprint" ""
			(at 327.66 170.18 0)
			(effects
				(font
					(size 1.27 1.27)
				)
				(justify left bottom)
				(hide yes)
			)
		)
		(property "Datasheet" ""
			(at 327.66 170.18 0)
			(effects
				(font
					(size 1.27 1.27)
				)
				(justify left bottom)
				(hide yes)
			)
		)
		(property "Description" ""
			(at 327.66 170.18 0)
			(effects
				(font
					(size 1.27 1.27)
				)
				(hide yes)
			)
		)
		(property "Author" "Antmicro"
			(at 318.77 177.8 0)
			(effects
				(font
					(size 1.27 1.27)
					(thickness 0.15)
				)
				(justify left bottom)
				(hide yes)
			)
		)
		(property "License" "Apache-2.0"
			(at 318.77 180.34 0)
			(effects
				(font
					(size 1.27 1.27)
					(thickness 0.15)
				)
				(justify left bottom)
				(hide yes)
			)
		)
		(pin "1"
		)
		(instances
			(project "com-express-7-baseboard"
				(path ""
					(reference "#PWR0426")
					(unit 1)
				)
				(path ""
					(reference "#PWR0375")
					(unit 1)
				)
			)
		)
	)
	(symbol
		(lib_id "antmicroResistors0402:R_10k_0402")
		(at 245.11 250.19 90)
		(unit 1)
		(exclude_from_sim no)
		(in_bom yes)
		(on_board yes)
		(dnp no)
		(property "Reference" "R271"
			(at 246.38 246.38 90)
			(effects
				(font
					(size 1.27 1.27)
					(thickness 0.15)
				)
				(justify right)
			)
		)
		(property "Value" "R_10k_0402"
			(at 257.81 229.87 0)
			(effects
				(font
					(size 1.27 1.27)
					(thickness 0.15)
				)
				(justify left bottom)
				(hide yes)
			)
		)
		(property "Footprint" "antmicro-footprints:R_0402_1005Metric"
			(at 260.35 229.87 0)
			(effects
				(font
					(size 1.27 1.27)
					(thickness 0.15)
				)
				(justify left bottom)
				(hide yes)
			)
		)
		(property "Datasheet" "https://www.bourns.com/docs/product-datasheets/cr.pdf"
			(at 262.89 229.87 0)
			(effects
				(font
					(size 1.27 1.27)
					(thickness 0.15)
				)
				(justify left bottom)
				(hide yes)
			)
		)
		(property "Description" ""
			(at 245.11 250.19 0)
			(effects
				(font
					(size 1.27 1.27)
				)
				(hide yes)
			)
		)
		(property "MPN" "CR0402-FX-1002GLF"
			(at 265.43 229.87 0)
			(effects
				(font
					(size 1.27 1.27)
					(thickness 0.15)
				)
				(justify left bottom)
				(hide yes)
			)
		)
		(property "Manufacturer" "Bourns"
			(at 267.97 229.87 0)
			(effects
				(font
					(size 1.27 1.27)
					(thickness 0.15)
				)
				(justify left bottom)
				(hide yes)
			)
		)
		(property "License" "Apache-2.0"
			(at 270.51 229.87 0)
			(effects
				(font
					(size 1.27 1.27)
					(thickness 0.15)
				)
				(justify left bottom)
				(hide yes)
			)
		)
		(property "Author" "Antmicro"
			(at 273.05 229.87 0)
			(effects
				(font
					(size 1.27 1.27)
					(thickness 0.15)
				)
				(justify left bottom)
				(hide yes)
			)
		)
		(property "Val" "10k"
			(at 246.38 248.92 90)
			(effects
				(font
					(size 1.27 1.27)
					(thickness 0.15)
				)
				(justify right)
			)
		)
		(property "Tolerance" "1%"
			(at 255.27 229.87 0)
			(effects
				(font
					(size 1.27 1.27)
				)
				(justify left bottom)
				(hide yes)
			)
		)
		(property "Public" "False"
			(at 275.59 229.87 0)
			(effects
				(font
					(size 1.27 1.27)
				)
				(justify left bottom)
				(hide yes)
			)
		)
		(pin "2"
		)
		(pin "1"
		)
		(instances
			(project "com-express-7-baseboard"
				(path ""
					(reference "R305")
					(unit 1)
				)
				(path ""
					(reference "R271")
					(unit 1)
				)
			)
		)
	)
	(symbol
		(lib_id "antmicroTestPoints:TP_0.75mm_SMD")
		(at 186.69 119.38 0)
		(unit 1)
		(exclude_from_sim no)
		(in_bom no)
		(on_board yes)
		(dnp no)
		(fields_autoplaced yes)
		(property "Reference" "TP72"
			(at 191.77 119.38 0)
			(effects
				(font
					(size 1.27 1.27)
					(thickness 0.15)
				)
				(justify left)
			)
		)
		(property "Value" "TP_0.75mm_SMD"
			(at 197.485 123.19 0)
			(effects
				(font
					(size 1.27 1.27)
					(thickness 0.15)
				)
				(justify left bottom)
				(hide yes)
			)
		)
		(property "Footprint" "antmicro-footprints:TP_SMD_0.75mm"
			(at 197.485 125.73 0)
			(effects
				(font
					(size 1.27 1.27)
					(thickness 0.15)
				)
				(justify left bottom)
				(hide yes)
			)
		)
		(property "Datasheet" ""
			(at 204.47 132.08 0)
			(effects
				(font
					(size 1.27 1.27)
					(thickness 0.15)
				)
				(justify left bottom)
				(hide yes)
			)
		)
		(property "Description" ""
			(at 186.69 119.38 0)
			(effects
				(font
					(size 1.27 1.27)
				)
				(hide yes)
			)
		)
		(property "MPN" ""
			(at 197.485 130.81 0)
			(effects
				(font
					(size 1.27 1.27)
					(thickness 0.15)
				)
				(justify left bottom)
				(hide yes)
			)
		)
		(property "Manufacturer" ""
			(at 197.485 125.73 0)
			(effects
				(font
					(size 1.27 1.27)
					(thickness 0.15)
				)
				(justify left bottom)
				(hide yes)
			)
		)
		(property "Author" "Antmicro"
			(at 197.485 128.27 0)
			(effects
				(font
					(size 1.27 1.27)
					(thickness 0.15)
				)
				(justify left bottom)
				(hide yes)
			)
		)
		(property "License" "Apache-2.0"
			(at 197.485 130.81 0)
			(effects
				(font
					(size 1.27 1.27)
					(thickness 0.15)
				)
				(justify left bottom)
				(hide yes)
			)
		)
		(property "Public" "False"
			(at 196.85 133.35 0)
			(effects
				(font
					(size 1.27 1.27)
				)
				(justify left bottom)
				(hide yes)
			)
		)
		(pin "1"
		)
		(instances
			(project "com-express-7-baseboard"
				(path ""
					(reference "TP92")
					(unit 1)
				)
				(path ""
					(reference "TP72")
					(unit 1)
				)
			)
		)
	)
	(symbol
		(lib_id "antmicropower:+1V0")
		(at 276.86 229.87 0)
		(unit 1)
		(exclude_from_sim no)
		(in_bom yes)
		(on_board yes)
		(dnp no)
		(fields_autoplaced yes)
		(property "Reference" "#PWR0361"
			(at 276.86 233.68 0)
			(effects
				(font
					(size 1.27 1.27)
				)
				(hide yes)
			)
		)
		(property "Value" "+1V0"
			(at 276.86 224.79 0)
			(effects
				(font
					(size 1.27 1.27)
				)
			)
		)
		(property "Footprint" ""
			(at 276.86 229.87 0)
			(effects
				(font
					(size 1.27 1.27)
				)
				(hide yes)
			)
		)
		(property "Datasheet" ""
			(at 276.86 229.87 0)
			(effects
				(font
					(size 1.27 1.27)
				)
				(hide yes)
			)
		)
		(property "Description" ""
			(at 276.86 229.87 0)
			(effects
				(font
					(size 1.27 1.27)
				)
				(hide yes)
			)
		)
		(pin "1"
		)
		(instances
			(project "com-express-7-baseboard"
				(path ""
					(reference "#PWR0412")
					(unit 1)
				)
				(path ""
					(reference "#PWR0361")
					(unit 1)
				)
			)
		)
	)
	(symbol
		(lib_id "antmicropower:GND")
		(at 62.23 198.12 0)
		(mirror y)
		(unit 1)
		(exclude_from_sim no)
		(in_bom yes)
		(on_board yes)
		(dnp no)
		(property "Reference" "#PWR0328"
			(at 62.23 204.47 0)
			(effects
				(font
					(size 1.27 1.27)
				)
				(justify left bottom)
				(hide yes)
			)
		)
		(property "Value" "GND"
			(at 62.23 201.93 0)
			(effects
				(font
					(size 1.27 1.27)
				)
			)
		)
		(property "Footprint" ""
			(at 62.23 198.12 0)
			(effects
				(font
					(size 1.27 1.27)
				)
				(justify left bottom)
				(hide yes)
			)
		)
		(property "Datasheet" ""
			(at 62.23 198.12 0)
			(effects
				(font
					(size 1.27 1.27)
				)
				(justify left bottom)
				(hide yes)
			)
		)
		(property "Description" ""
			(at 62.23 198.12 0)
			(effects
				(font
					(size 1.27 1.27)
				)
				(hide yes)
			)
		)
		(property "Author" "Antmicro"
			(at 53.34 205.74 0)
			(effects
				(font
					(size 1.27 1.27)
					(thickness 0.15)
				)
				(justify left bottom)
				(hide yes)
			)
		)
		(property "License" "Apache-2.0"
			(at 53.34 208.28 0)
			(effects
				(font
					(size 1.27 1.27)
					(thickness 0.15)
				)
				(justify left bottom)
				(hide yes)
			)
		)
		(pin "1"
		)
		(instances
			(project "com-express-7-baseboard"
				(path ""
					(reference "#PWR0379")
					(unit 1)
				)
				(path ""
					(reference "#PWR0328")
					(unit 1)
				)
			)
		)
	)
	(symbol
		(lib_id "antmicroTestPoints:TP_0.75mm_SMD")
		(at 149.86 215.9 0)
		(mirror y)
		(unit 1)
		(exclude_from_sim no)
		(in_bom no)
		(on_board yes)
		(dnp no)
		(fields_autoplaced yes)
		(property "Reference" "TP63"
			(at 144.78 215.9 0)
			(effects
				(font
					(size 1.27 1.27)
					(thickness 0.15)
				)
				(justify left)
			)
		)
		(property "Value" "TP_0.75mm_SMD"
			(at 139.065 219.71 0)
			(effects
				(font
					(size 1.27 1.27)
					(thickness 0.15)
				)
				(justify left bottom)
				(hide yes)
			)
		)
		(property "Footprint" "antmicro-footprints:TP_SMD_0.75mm"
			(at 139.065 222.25 0)
			(effects
				(font
					(size 1.27 1.27)
					(thickness 0.15)
				)
				(justify left bottom)
				(hide yes)
			)
		)
		(property "Datasheet" ""
			(at 132.08 228.6 0)
			(effects
				(font
					(size 1.27 1.27)
					(thickness 0.15)
				)
				(justify left bottom)
				(hide yes)
			)
		)
		(property "Description" ""
			(at 149.86 215.9 0)
			(effects
				(font
					(size 1.27 1.27)
				)
				(hide yes)
			)
		)
		(property "MPN" ""
			(at 139.065 227.33 0)
			(effects
				(font
					(size 1.27 1.27)
					(thickness 0.15)
				)
				(justify left bottom)
				(hide yes)
			)
		)
		(property "Manufacturer" ""
			(at 139.065 222.25 0)
			(effects
				(font
					(size 1.27 1.27)
					(thickness 0.15)
				)
				(justify left bottom)
				(hide yes)
			)
		)
		(property "Author" "Antmicro"
			(at 139.065 224.79 0)
			(effects
				(font
					(size 1.27 1.27)
					(thickness 0.15)
				)
				(justify left bottom)
				(hide yes)
			)
		)
		(property "License" "Apache-2.0"
			(at 139.065 227.33 0)
			(effects
				(font
					(size 1.27 1.27)
					(thickness 0.15)
				)
				(justify left bottom)
				(hide yes)
			)
		)
		(property "Public" "False"
			(at 139.7 229.87 0)
			(effects
				(font
					(size 1.27 1.27)
				)
				(justify left bottom)
				(hide yes)
			)
		)
		(pin "1"
		)
		(instances
			(project "com-express-7-baseboard"
				(path ""
					(reference "TP83")
					(unit 1)
				)
				(path ""
					(reference "TP63")
					(unit 1)
				)
			)
		)
	)
	(symbol
		(lib_id "antmicroTestPoints:TP_0.75mm_SMD")
		(at 227.33 116.84 0)
		(mirror y)
		(unit 1)
		(exclude_from_sim no)
		(in_bom no)
		(on_board yes)
		(dnp no)
		(fields_autoplaced yes)
		(property "Reference" "TP74"
			(at 222.25 116.84 0)
			(effects
				(font
					(size 1.27 1.27)
					(thickness 0.15)
				)
				(justify left)
			)
		)
		(property "Value" "TP_0.75mm_SMD"
			(at 216.535 120.65 0)
			(effects
				(font
					(size 1.27 1.27)
					(thickness 0.15)
				)
				(justify left bottom)
				(hide yes)
			)
		)
		(property "Footprint" "antmicro-footprints:TP_SMD_0.75mm"
			(at 216.535 123.19 0)
			(effects
				(font
					(size 1.27 1.27)
					(thickness 0.15)
				)
				(justify left bottom)
				(hide yes)
			)
		)
		(property "Datasheet" ""
			(at 209.55 129.54 0)
			(effects
				(font
					(size 1.27 1.27)
					(thickness 0.15)
				)
				(justify left bottom)
				(hide yes)
			)
		)
		(property "Description" ""
			(at 227.33 116.84 0)
			(effects
				(font
					(size 1.27 1.27)
				)
				(hide yes)
			)
		)
		(property "MPN" ""
			(at 216.535 128.27 0)
			(effects
				(font
					(size 1.27 1.27)
					(thickness 0.15)
				)
				(justify left bottom)
				(hide yes)
			)
		)
		(property "Manufacturer" ""
			(at 216.535 123.19 0)
			(effects
				(font
					(size 1.27 1.27)
					(thickness 0.15)
				)
				(justify left bottom)
				(hide yes)
			)
		)
		(property "Author" "Antmicro"
			(at 216.535 125.73 0)
			(effects
				(font
					(size 1.27 1.27)
					(thickness 0.15)
				)
				(justify left bottom)
				(hide yes)
			)
		)
		(property "License" "Apache-2.0"
			(at 216.535 128.27 0)
			(effects
				(font
					(size 1.27 1.27)
					(thickness 0.15)
				)
				(justify left bottom)
				(hide yes)
			)
		)
		(property "Public" "False"
			(at 217.17 130.81 0)
			(effects
				(font
					(size 1.27 1.27)
				)
				(justify left bottom)
				(hide yes)
			)
		)
		(pin "1"
		)
		(instances
			(project "com-express-7-baseboard"
				(path ""
					(reference "TP94")
					(unit 1)
				)
				(path ""
					(reference "TP74")
					(unit 1)
				)
			)
		)
	)
	(symbol
		(lib_id "antmicropower:GND")
		(at 140.97 248.92 0)
		(mirror y)
		(unit 1)
		(exclude_from_sim no)
		(in_bom yes)
		(on_board yes)
		(dnp no)
		(fields_autoplaced yes)
		(property "Reference" "#PWR0338"
			(at 140.97 255.27 0)
			(effects
				(font
					(size 1.27 1.27)
				)
				(justify left bottom)
				(hide yes)
			)
		)
		(property "Value" "GND"
			(at 140.97 254 0)
			(effects
				(font
					(size 1.27 1.27)
				)
			)
		)
		(property "Footprint" ""
			(at 140.97 248.92 0)
			(effects
				(font
					(size 1.27 1.27)
				)
				(justify left bottom)
				(hide yes)
			)
		)
		(property "Datasheet" ""
			(at 140.97 248.92 0)
			(effects
				(font
					(size 1.27 1.27)
				)
				(justify left bottom)
				(hide yes)
			)
		)
		(property "Description" ""
			(at 140.97 248.92 0)
			(effects
				(font
					(size 1.27 1.27)
				)
				(hide yes)
			)
		)
		(property "Author" "Antmicro"
			(at 132.08 256.54 0)
			(effects
				(font
					(size 1.27 1.27)
					(thickness 0.15)
				)
				(justify left bottom)
				(hide yes)
			)
		)
		(property "License" "Apache-2.0"
			(at 132.08 259.08 0)
			(effects
				(font
					(size 1.27 1.27)
					(thickness 0.15)
				)
				(justify left bottom)
				(hide yes)
			)
		)
		(pin "1"
		)
		(instances
			(project "com-express-7-baseboard"
				(path ""
					(reference "#PWR0389")
					(unit 1)
				)
				(path ""
					(reference "#PWR0338")
					(unit 1)
				)
			)
		)
	)
	(symbol
		(lib_id "antmicropower:GND")
		(at 307.34 193.04 0)
		(mirror y)
		(unit 1)
		(exclude_from_sim no)
		(in_bom yes)
		(on_board yes)
		(dnp no)
		(fields_autoplaced yes)
		(property "Reference" "#PWR0371"
			(at 307.34 199.39 0)
			(effects
				(font
					(size 1.27 1.27)
				)
				(justify left bottom)
				(hide yes)
			)
		)
		(property "Value" "GND"
			(at 307.34 198.12 0)
			(effects
				(font
					(size 1.27 1.27)
				)
			)
		)
		(property "Footprint" ""
			(at 307.34 193.04 0)
			(effects
				(font
					(size 1.27 1.27)
				)
				(justify left bottom)
				(hide yes)
			)
		)
		(property "Datasheet" ""
			(at 307.34 193.04 0)
			(effects
				(font
					(size 1.27 1.27)
				)
				(justify left bottom)
				(hide yes)
			)
		)
		(property "Description" ""
			(at 307.34 193.04 0)
			(effects
				(font
					(size 1.27 1.27)
				)
				(hide yes)
			)
		)
		(property "Author" "Antmicro"
			(at 298.45 200.66 0)
			(effects
				(font
					(size 1.27 1.27)
					(thickness 0.15)
				)
				(justify left bottom)
				(hide yes)
			)
		)
		(property "License" "Apache-2.0"
			(at 298.45 203.2 0)
			(effects
				(font
					(size 1.27 1.27)
					(thickness 0.15)
				)
				(justify left bottom)
				(hide yes)
			)
		)
		(pin "1"
		)
		(instances
			(project "com-express-7-baseboard"
				(path ""
					(reference "#PWR0422")
					(unit 1)
				)
				(path ""
					(reference "#PWR0371")
					(unit 1)
				)
			)
		)
	)
	(symbol
		(lib_id "antmicroCapacitors0402:C_100n_0402")
		(at 287.02 238.76 90)
		(unit 1)
		(exclude_from_sim no)
		(in_bom yes)
		(on_board yes)
		(dnp no)
		(fields_autoplaced yes)
		(property "Reference" "C164"
			(at 289.56 234.9436 90)
			(effects
				(font
					(size 1.27 1.27)
					(thickness 0.15)
				)
				(justify right)
			)
		)
		(property "Value" "C_100n_0402"
			(at 297.18 218.44 0)
			(effects
				(font
					(size 1.27 1.27)
					(thickness 0.15)
				)
				(justify left bottom)
				(hide yes)
			)
		)
		(property "Footprint" "antmicro-footprints:C_0402_1005Metric"
			(at 299.72 218.44 0)
			(effects
				(font
					(size 1.27 1.27)
					(thickness 0.15)
				)
				(justify left bottom)
				(hide yes)
			)
		)
		(property "Datasheet" "https://www.murata.com/products/productdetail?partno=GRM155R61H104KE14%23"
			(at 302.26 218.44 0)
			(effects
				(font
					(size 1.27 1.27)
					(thickness 0.15)
				)
				(justify left bottom)
				(hide yes)
			)
		)
		(property "Description" ""
			(at 287.02 238.76 0)
			(effects
				(font
					(size 1.27 1.27)
				)
				(hide yes)
			)
		)
		(property "MPN" "GRM155R61H104KE14D"
			(at 304.8 218.44 0)
			(effects
				(font
					(size 1.27 1.27)
					(thickness 0.15)
				)
				(justify left bottom)
				(hide yes)
			)
		)
		(property "Manufacturer" "Murata"
			(at 307.34 218.44 0)
			(effects
				(font
					(size 1.27 1.27)
					(thickness 0.15)
				)
				(justify left bottom)
				(hide yes)
			)
		)
		(property "License" "Apache-2.0"
			(at 309.88 218.44 0)
			(effects
				(font
					(size 1.27 1.27)
					(thickness 0.15)
				)
				(justify left bottom)
				(hide yes)
			)
		)
		(property "Author" "Antmicro"
			(at 312.42 218.44 0)
			(effects
				(font
					(size 1.27 1.27)
					(thickness 0.15)
				)
				(justify left bottom)
				(hide yes)
			)
		)
		(property "Val" "100n"
			(at 289.56 237.4836 90)
			(effects
				(font
					(size 1.27 1.27)
					(thickness 0.15)
				)
				(justify right)
			)
		)
		(property "Voltage" "50V"
			(at 314.96 218.44 0)
			(effects
				(font
					(size 1.27 1.27)
				)
				(justify left bottom)
				(hide yes)
			)
		)
		(property "Dielectric" "X5R"
			(at 317.5 218.44 0)
			(effects
				(font
					(size 1.27 1.27)
				)
				(justify left bottom)
				(hide yes)
			)
		)
		(property "Public" "False"
			(at 320.04 218.44 0)
			(effects
				(font
					(size 1.27 1.27)
				)
				(justify left bottom)
				(hide yes)
			)
		)
		(pin "2"
		)
		(pin "1"
		)
		(instances
			(project "com-express-7-baseboard"
				(path ""
					(reference "C191")
					(unit 1)
				)
				(path ""
					(reference "C164")
					(unit 1)
				)
			)
		)
	)
	(symbol
		(lib_id "antmicropower:GND")
		(at 276.86 170.18 0)
		(mirror y)
		(unit 1)
		(exclude_from_sim no)
		(in_bom yes)
		(on_board yes)
		(dnp no)
		(fields_autoplaced yes)
		(property "Reference" "#PWR0356"
			(at 276.86 176.53 0)
			(effects
				(font
					(size 1.27 1.27)
				)
				(justify left bottom)
				(hide yes)
			)
		)
		(property "Value" "GND"
			(at 276.86 175.26 0)
			(effects
				(font
					(size 1.27 1.27)
				)
			)
		)
		(property "Footprint" ""
			(at 276.86 170.18 0)
			(effects
				(font
					(size 1.27 1.27)
				)
				(justify left bottom)
				(hide yes)
			)
		)
		(property "Datasheet" ""
			(at 276.86 170.18 0)
			(effects
				(font
					(size 1.27 1.27)
				)
				(justify left bottom)
				(hide yes)
			)
		)
		(property "Description" ""
			(at 276.86 170.18 0)
			(effects
				(font
					(size 1.27 1.27)
				)
				(hide yes)
			)
		)
		(property "Author" "Antmicro"
			(at 267.97 177.8 0)
			(effects
				(font
					(size 1.27 1.27)
					(thickness 0.15)
				)
				(justify left bottom)
				(hide yes)
			)
		)
		(property "License" "Apache-2.0"
			(at 267.97 180.34 0)
			(effects
				(font
					(size 1.27 1.27)
					(thickness 0.15)
				)
				(justify left bottom)
				(hide yes)
			)
		)
		(pin "1"
		)
		(instances
			(project "com-express-7-baseboard"
				(path ""
					(reference "#PWR0407")
					(unit 1)
				)
				(path ""
					(reference "#PWR0356")
					(unit 1)
				)
			)
		)
	)
	(symbol
		(lib_id "antmicroResistors0402:R_10k_0402")
		(at 237.49 250.19 90)
		(unit 1)
		(exclude_from_sim no)
		(in_bom yes)
		(on_board yes)
		(dnp no)
		(property "Reference" "R269"
			(at 238.76 246.38 90)
			(effects
				(font
					(size 1.27 1.27)
					(thickness 0.15)
				)
				(justify right)
			)
		)
		(property "Value" "R_10k_0402"
			(at 250.19 229.87 0)
			(effects
				(font
					(size 1.27 1.27)
					(thickness 0.15)
				)
				(justify left bottom)
				(hide yes)
			)
		)
		(property "Footprint" "antmicro-footprints:R_0402_1005Metric"
			(at 252.73 229.87 0)
			(effects
				(font
					(size 1.27 1.27)
					(thickness 0.15)
				)
				(justify left bottom)
				(hide yes)
			)
		)
		(property "Datasheet" "https://www.bourns.com/docs/product-datasheets/cr.pdf"
			(at 255.27 229.87 0)
			(effects
				(font
					(size 1.27 1.27)
					(thickness 0.15)
				)
				(justify left bottom)
				(hide yes)
			)
		)
		(property "Description" ""
			(at 237.49 250.19 0)
			(effects
				(font
					(size 1.27 1.27)
				)
				(hide yes)
			)
		)
		(property "MPN" "CR0402-FX-1002GLF"
			(at 257.81 229.87 0)
			(effects
				(font
					(size 1.27 1.27)
					(thickness 0.15)
				)
				(justify left bottom)
				(hide yes)
			)
		)
		(property "Manufacturer" "Bourns"
			(at 260.35 229.87 0)
			(effects
				(font
					(size 1.27 1.27)
					(thickness 0.15)
				)
				(justify left bottom)
				(hide yes)
			)
		)
		(property "License" "Apache-2.0"
			(at 262.89 229.87 0)
			(effects
				(font
					(size 1.27 1.27)
					(thickness 0.15)
				)
				(justify left bottom)
				(hide yes)
			)
		)
		(property "Author" "Antmicro"
			(at 265.43 229.87 0)
			(effects
				(font
					(size 1.27 1.27)
					(thickness 0.15)
				)
				(justify left bottom)
				(hide yes)
			)
		)
		(property "Val" "10k"
			(at 238.76 248.92 90)
			(effects
				(font
					(size 1.27 1.27)
					(thickness 0.15)
				)
				(justify right)
			)
		)
		(property "Tolerance" "1%"
			(at 247.65 229.87 0)
			(effects
				(font
					(size 1.27 1.27)
				)
				(justify left bottom)
				(hide yes)
			)
		)
		(property "Public" "False"
			(at 267.97 229.87 0)
			(effects
				(font
					(size 1.27 1.27)
				)
				(justify left bottom)
				(hide yes)
			)
		)
		(pin "2"
		)
		(pin "1"
		)
		(instances
			(project "com-express-7-baseboard"
				(path ""
					(reference "R303")
					(unit 1)
				)
				(path ""
					(reference "R269")
					(unit 1)
				)
			)
		)
	)
	(symbol
		(lib_id "antmicroTestPoints:TP_0.75mm_SMD")
		(at 227.33 119.38 0)
		(mirror y)
		(unit 1)
		(exclude_from_sim no)
		(in_bom no)
		(on_board yes)
		(dnp no)
		(fields_autoplaced yes)
		(property "Reference" "TP75"
			(at 222.25 119.38 0)
			(effects
				(font
					(size 1.27 1.27)
					(thickness 0.15)
				)
				(justify left)
			)
		)
		(property "Value" "TP_0.75mm_SMD"
			(at 216.535 123.19 0)
			(effects
				(font
					(size 1.27 1.27)
					(thickness 0.15)
				)
				(justify left bottom)
				(hide yes)
			)
		)
		(property "Footprint" "antmicro-footprints:TP_SMD_0.75mm"
			(at 216.535 125.73 0)
			(effects
				(font
					(size 1.27 1.27)
					(thickness 0.15)
				)
				(justify left bottom)
				(hide yes)
			)
		)
		(property "Datasheet" ""
			(at 209.55 132.08 0)
			(effects
				(font
					(size 1.27 1.27)
					(thickness 0.15)
				)
				(justify left bottom)
				(hide yes)
			)
		)
		(property "Description" ""
			(at 227.33 119.38 0)
			(effects
				(font
					(size 1.27 1.27)
				)
				(hide yes)
			)
		)
		(property "MPN" ""
			(at 216.535 130.81 0)
			(effects
				(font
					(size 1.27 1.27)
					(thickness 0.15)
				)
				(justify left bottom)
				(hide yes)
			)
		)
		(property "Manufacturer" ""
			(at 216.535 125.73 0)
			(effects
				(font
					(size 1.27 1.27)
					(thickness 0.15)
				)
				(justify left bottom)
				(hide yes)
			)
		)
		(property "Author" "Antmicro"
			(at 216.535 128.27 0)
			(effects
				(font
					(size 1.27 1.27)
					(thickness 0.15)
				)
				(justify left bottom)
				(hide yes)
			)
		)
		(property "License" "Apache-2.0"
			(at 216.535 130.81 0)
			(effects
				(font
					(size 1.27 1.27)
					(thickness 0.15)
				)
				(justify left bottom)
				(hide yes)
			)
		)
		(property "Public" "False"
			(at 217.17 133.35 0)
			(effects
				(font
					(size 1.27 1.27)
				)
				(justify left bottom)
				(hide yes)
			)
		)
		(pin "1"
		)
		(instances
			(project "com-express-7-baseboard"
				(path ""
					(reference "TP95")
					(unit 1)
				)
				(path ""
					(reference "TP75")
					(unit 1)
				)
			)
		)
	)
	(symbol
		(lib_id "antmicropower:GND")
		(at 215.9 250.19 0)
		(mirror y)
		(unit 1)
		(exclude_from_sim no)
		(in_bom yes)
		(on_board yes)
		(dnp no)
		(fields_autoplaced yes)
		(property "Reference" "#PWR0346"
			(at 215.9 256.54 0)
			(effects
				(font
					(size 1.27 1.27)
				)
				(justify left bottom)
				(hide yes)
			)
		)
		(property "Value" "GND"
			(at 215.9 255.27 0)
			(effects
				(font
					(size 1.27 1.27)
				)
			)
		)
		(property "Footprint" ""
			(at 215.9 250.19 0)
			(effects
				(font
					(size 1.27 1.27)
				)
				(justify left bottom)
				(hide yes)
			)
		)
		(property "Datasheet" ""
			(at 215.9 250.19 0)
			(effects
				(font
					(size 1.27 1.27)
				)
				(justify left bottom)
				(hide yes)
			)
		)
		(property "Description" ""
			(at 215.9 250.19 0)
			(effects
				(font
					(size 1.27 1.27)
				)
				(hide yes)
			)
		)
		(property "Author" "Antmicro"
			(at 207.01 257.81 0)
			(effects
				(font
					(size 1.27 1.27)
					(thickness 0.15)
				)
				(justify left bottom)
				(hide yes)
			)
		)
		(property "License" "Apache-2.0"
			(at 207.01 260.35 0)
			(effects
				(font
					(size 1.27 1.27)
					(thickness 0.15)
				)
				(justify left bottom)
				(hide yes)
			)
		)
		(pin "1"
		)
		(instances
			(project "com-express-7-baseboard"
				(path ""
					(reference "#PWR0397")
					(unit 1)
				)
				(path ""
					(reference "#PWR0346")
					(unit 1)
				)
			)
		)
	)
	(symbol
		(lib_id "antmicroResistorsmisc:R_0R_0201")
		(at 287.02 86.36 0)
		(unit 1)
		(exclude_from_sim no)
		(in_bom yes)
		(on_board yes)
		(dnp no)
		(property "Reference" "R275"
			(at 284.48 87.63 0)
			(effects
				(font
					(size 1.27 1.27)
					(thickness 0.15)
				)
			)
		)
		(property "Value" "R_0R_0201"
			(at 307.34 99.06 0)
			(effects
				(font
					(size 1.27 1.27)
					(thickness 0.15)
				)
				(justify left bottom)
				(hide yes)
			)
		)
		(property "Footprint" "antmicro-footprints:R_0201"
			(at 307.34 101.6 0)
			(effects
				(font
					(size 1.27 1.27)
					(thickness 0.15)
				)
				(justify left bottom)
				(hide yes)
			)
		)
		(property "Datasheet" "https://www.bourns.com/docs/product-datasheets/cr.pdf"
			(at 307.34 104.14 0)
			(effects
				(font
					(size 1.27 1.27)
					(thickness 0.15)
				)
				(justify left bottom)
				(hide yes)
			)
		)
		(property "Description" ""
			(at 287.02 86.36 0)
			(effects
				(font
					(size 1.27 1.27)
				)
				(hide yes)
			)
		)
		(property "MPN" "CR0201-FX-0R00GLF"
			(at 307.34 106.68 0)
			(effects
				(font
					(size 1.27 1.27)
					(thickness 0.15)
				)
				(justify left bottom)
				(hide yes)
			)
		)
		(property "Manufacturer" "Bourns"
			(at 307.34 109.22 0)
			(effects
				(font
					(size 1.27 1.27)
					(thickness 0.15)
				)
				(justify left bottom)
				(hide yes)
			)
		)
		(property "License" "Apache-2.0"
			(at 307.34 111.76 0)
			(effects
				(font
					(size 1.27 1.27)
					(thickness 0.15)
				)
				(justify left bottom)
				(hide yes)
			)
		)
		(property "Author" "Antmicro"
			(at 307.34 114.3 0)
			(effects
				(font
					(size 1.27 1.27)
					(thickness 0.15)
				)
				(justify left bottom)
				(hide yes)
			)
		)
		(property "Val" "0R"
			(at 293.37 87.63 0)
			(effects
				(font
					(size 1.27 1.27)
					(thickness 0.15)
				)
			)
		)
		(property "Tolerance" "1%"
			(at 307.34 96.52 0)
			(effects
				(font
					(size 1.27 1.27)
				)
				(justify left bottom)
				(hide yes)
			)
		)
		(pin "1"
		)
		(pin "2"
		)
		(instances
			(project "com-express-7-baseboard"
				(path ""
					(reference "R309")
					(unit 1)
				)
				(path ""
					(reference "R275")
					(unit 1)
				)
			)
		)
	)
)
